FILE_TYPE = MACRO_DRAWING;
SET COLOR_WIRE YELLOW;
SET COLOR_PROP ORANGE;
SET COLOR_DOT WHITE;
SET COLOR_ARC YELLOW;
SET COLOR_BODY GREEN;
SET COLOR_NOTE PURPLE;
SET PROP_DISPLAY VALUE;
SET PAGE_NUMBER P6;
FORCEADD RESISTOR..1
(-5600 1600);
FORCEPROP 1 LAST $LOCATION R407
J 2
(-5800 1600);
DISPLAY 1.212766 (-5800 1600);
PAINT GREEN (-5800 1600);
FORCEPROP 0 LAST CDS_LOCATION R407
J 0
(-5350 1700);
DISPLAY 1.021277 (-5350 1700);
DISPLAY INVISIBLE (-5350 1700);
FORCEPROP 0 LAST $SEC 1
J 0
(-5350 1700);
DISPLAY 0.680851 (-5350 1700);
PAINT MONO (-5350 1700);
DISPLAY INVISIBLE (-5350 1700);
FORCEPROP 0 LAST CDS_SEC 1
J 0
(-5350 1700);
DISPLAY 1.021277 (-5350 1700);
DISPLAY INVISIBLE (-5350 1700);
FORCEPROP 0 LASTPIN (-5700 1600) $PN 1
J 2
(-5710 1610);
DISPLAY 0.680851 (-5710 1610);
PAINT MONO (-5710 1610);
FORCEPROP 0 LASTPIN (-5450 1600) $PN 2
J 0
(-5440 1610);
DISPLAY 0.680851 (-5440 1610);
PAINT MONO (-5440 1610);
FORCEPROP 1 LAST VALUE 33OHM
J 0
(-5361 1605);
DISPLAY 1.212766 (-5361 1605);
PAINT GREEN (-5361 1605);
FORCEPROP 0 LAST PACKAGE 0402
J 0
(-5650 1500);
DISPLAY 1.021277 (-5650 1500);
FORCEPROP 1 LAST PATH I100
J 0
(-5797 1705);
DISPLAY 1.212766 (-5797 1705);
PAINT GREEN (-5797 1705);
DISPLAY INVISIBLE (-5797 1705);
FORCEPROP 1 LAST TOLERANCE 1%
J 0
(-5797 1855);
DISPLAY 1.212766 (-5797 1855);
PAINT GREEN (-5797 1855);
DISPLAY INVISIBLE (-5797 1855);
FORCEPROP 2 LAST CDS_LIB passive
J 0
(-5600 1600);
DISPLAY INVISIBLE (-5600 1600);
FORCEPROP 1 LAST CDS_LMAN_SYM_OUTLINE -50,50,100,-50
J 0
(-5600 1600);
DISPLAY 0.468085 (-5600 1600);
PAINT GREEN (-5600 1600);
DISPLAY INVISIBLE (-5600 1600);
FORCEPROP 1 LAST CLS_PN G155-133R0-01
J 0
(-5736 1800);
DISPLAY 1.212766 (-5736 1800);
PAINT GREEN (-5736 1800);
DISPLAY INVISIBLE (-5736 1800);
FORCEADD OFFPAGE_BI..2
(-8350 7600);
FORCEPROP 2 LAST PATH I12
J 0
(-8550 7650);
DISPLAY 1.021277 (-8550 7650);
DISPLAY INVISIBLE (-8550 7650);
FORCEPROP 1 LAST OFFPAGE TRUE
J 0
(-8340 7655);
DISPLAY 0.808511 (-8340 7655);
PAINT GREEN (-8340 7655);
DISPLAY INVISIBLE (-8340 7655);
FORCEPROP 1 LAST BODY_TYPE COMMENT
J 0
(-8340 7735);
DISPLAY 0.808511 (-8340 7735);
PAINT GREEN (-8340 7735);
DISPLAY INVISIBLE (-8340 7735);
FORCEPROP 1 LAST CDS_LMAN_SYM_OUTLINE -50,50,50,-50
J 0
(-8350 7600);
DISPLAY 0.468085 (-8350 7600);
PAINT GREEN (-8350 7600);
DISPLAY INVISIBLE (-8350 7600);
FORCEPROP 2 LAST CDS_LIB cls
J 0
(-8350 7600);
PAINT MONO (-8350 7600);
DISPLAY INVISIBLE (-8350 7600);
FORCEPROP 2 LAST $XR0 16C12<> 
J 0
(-8600 7600);
DISPLAY 0.638298 (-8600 7600);
PAINT MONO (-8600 7600);
FORCEADD OFFPAGE_BI..2
(-8350 7700);
FORCEPROP 2 LAST PATH I13
J 0
(-8500 7750);
DISPLAY 1.021277 (-8500 7750);
DISPLAY INVISIBLE (-8500 7750);
FORCEPROP 1 LAST OFFPAGE TRUE
J 0
(-8340 7755);
DISPLAY 0.808511 (-8340 7755);
PAINT GREEN (-8340 7755);
DISPLAY INVISIBLE (-8340 7755);
FORCEPROP 1 LAST CDS_LMAN_SYM_OUTLINE -50,50,50,-50
J 0
(-8350 7700);
DISPLAY 0.468085 (-8350 7700);
PAINT GREEN (-8350 7700);
DISPLAY INVISIBLE (-8350 7700);
FORCEPROP 1 LAST BODY_TYPE COMMENT
J 0
(-8340 7835);
DISPLAY 0.808511 (-8340 7835);
PAINT GREEN (-8340 7835);
DISPLAY INVISIBLE (-8340 7835);
FORCEPROP 2 LAST CDS_LIB cls
J 0
(-8350 7700);
PAINT MONO (-8350 7700);
DISPLAY INVISIBLE (-8350 7700);
FORCEPROP 2 LAST $XR0 16C12> 
J 0
(-8569 7700);
DISPLAY 0.638298 (-8569 7700);
PAINT MONO (-8569 7700);
FORCEADD RESISTOR..2
(-5900 8150);
FORCEPROP 1 LAST $LOCATION R20
J 0
(-5850 8000);
DISPLAY 1.212766 (-5850 8000);
PAINT GREEN (-5850 8000);
FORCEPROP 0 LAST CDS_LOCATION R20
J 0
(-5850 8000);
DISPLAY 1.212766 (-5850 8000);
PAINT GREEN (-5850 8000);
DISPLAY INVISIBLE (-5850 8000);
FORCEPROP 0 LAST $SEC 1
J 0
(-5850 8250);
DISPLAY 0.680851 (-5850 8250);
PAINT MONO (-5850 8250);
DISPLAY INVISIBLE (-5850 8250);
FORCEPROP 0 LAST CDS_SEC 1
J 0
(-5850 8250);
DISPLAY 1.021277 (-5850 8250);
DISPLAY INVISIBLE (-5850 8250);
FORCEPROP 0 LASTPIN (-5900 8250) $PN 1
R 1
J 0
(-5910 8260);
DISPLAY 0.680851 (-5910 8260);
PAINT MONO (-5910 8260);
FORCEPROP 0 LASTPIN (-5900 8000) $PN 2
R 1
J 2
(-5910 7990);
DISPLAY 0.680851 (-5910 7990);
PAINT MONO (-5910 7990);
FORCEPROP 0 LAST PACKAGE 0402
J 0
(-5850 8300);
DISPLAY 1.021277 (-5850 8300);
FORCEPROP 1 LAST VALUE 4.7KOHM
J 0
(-5850 8200);
DISPLAY 0.978723 (-5850 8200);
PAINT GREEN (-5850 8200);
FORCEPROP 1 LAST PATH I14
J 0
(-6097 8255);
DISPLAY 1.212766 (-6097 8255);
PAINT GREEN (-6097 8255);
DISPLAY INVISIBLE (-6097 8255);
FORCEPROP 1 LAST TOLERANCE 1%
J 0
(-6097 8405);
DISPLAY 1.212766 (-6097 8405);
PAINT GREEN (-6097 8405);
DISPLAY INVISIBLE (-6097 8405);
FORCEPROP 1 LAST CDS_LMAN_SYM_OUTLINE -50,50,50,-100
J 0
(-5900 8150);
DISPLAY 0.468085 (-5900 8150);
PAINT GREEN (-5900 8150);
DISPLAY INVISIBLE (-5900 8150);
FORCEPROP 2 LAST CDS_LIB passive
J 0
(-5900 8150);
DISPLAY INVISIBLE (-5900 8150);
FORCEPROP 1 LAST CLS_PN G155-14701-01
J 0
(-6036 8350);
DISPLAY 1.212766 (-6036 8350);
PAINT GREEN (-6036 8350);
DISPLAY INVISIBLE (-6036 8350);
FORCEADD RESISTOR..1
(-5350 7600);
FORCEPROP 1 LAST $LOCATION R332
J 2
(-5501 7605);
DISPLAY 1.212766 (-5501 7605);
PAINT GREEN (-5501 7605);
FORCEPROP 0 LAST CDS_LOCATION R332
J 2
(-5501 7605);
DISPLAY 1.212766 (-5501 7605);
PAINT GREEN (-5501 7605);
DISPLAY INVISIBLE (-5501 7605);
FORCEPROP 0 LAST $SEC 1
J 0
(-5100 7700);
DISPLAY 0.680851 (-5100 7700);
PAINT MONO (-5100 7700);
DISPLAY INVISIBLE (-5100 7700);
FORCEPROP 0 LAST CDS_SEC 1
J 0
(-5100 7700);
DISPLAY 1.021277 (-5100 7700);
DISPLAY INVISIBLE (-5100 7700);
FORCEPROP 0 LASTPIN (-5450 7600) $PN 1
J 2
(-5460 7610);
DISPLAY 0.680851 (-5460 7610);
PAINT MONO (-5460 7610);
FORCEPROP 0 LASTPIN (-5200 7600) $PN 2
J 0
(-5190 7610);
DISPLAY 0.680851 (-5190 7610);
PAINT MONO (-5190 7610);
FORCEPROP 1 LAST VALUE 33OHM
J 0
(-5111 7605);
DISPLAY 1.212766 (-5111 7605);
PAINT GREEN (-5111 7605);
FORCEPROP 0 LAST PACKAGE 0402
J 0
(-5400 7500);
DISPLAY 1.021277 (-5400 7500);
FORCEPROP 1 LAST PATH I15
J 0
(-5547 7705);
DISPLAY 1.212766 (-5547 7705);
PAINT GREEN (-5547 7705);
DISPLAY INVISIBLE (-5547 7705);
FORCEPROP 1 LAST TOLERANCE 1%
J 0
(-5547 7855);
DISPLAY 1.212766 (-5547 7855);
PAINT GREEN (-5547 7855);
DISPLAY INVISIBLE (-5547 7855);
FORCEPROP 1 LAST CLS_PN G155-133R0-01
J 0
(-5486 7800);
DISPLAY 1.212766 (-5486 7800);
PAINT GREEN (-5486 7800);
DISPLAY INVISIBLE (-5486 7800);
FORCEPROP 2 LAST CDS_LIB passive
J 0
(-5350 7600);
DISPLAY INVISIBLE (-5350 7600);
FORCEPROP 1 LAST CDS_LMAN_SYM_OUTLINE -50,50,100,-50
J 0
(-5350 7600);
DISPLAY 0.468085 (-5350 7600);
PAINT GREEN (-5350 7600);
DISPLAY INVISIBLE (-5350 7600);
FORCEADD RESISTOR..2
(-5350 8150);
FORCEPROP 1 LAST $LOCATION R21
J 0
(-5300 8000);
DISPLAY 1.212766 (-5300 8000);
PAINT GREEN (-5300 8000);
FORCEPROP 0 LAST CDS_LOCATION R21
J 0
(-5300 8000);
DISPLAY 1.212766 (-5300 8000);
PAINT GREEN (-5300 8000);
DISPLAY INVISIBLE (-5300 8000);
FORCEPROP 0 LAST $SEC 1
J 0
(-5300 8250);
DISPLAY 0.680851 (-5300 8250);
PAINT MONO (-5300 8250);
DISPLAY INVISIBLE (-5300 8250);
FORCEPROP 0 LAST CDS_SEC 1
J 0
(-5300 8250);
DISPLAY 1.021277 (-5300 8250);
DISPLAY INVISIBLE (-5300 8250);
FORCEPROP 0 LASTPIN (-5350 8250) $PN 1
R 1
J 0
(-5360 8260);
DISPLAY 0.680851 (-5360 8260);
PAINT MONO (-5360 8260);
FORCEPROP 0 LASTPIN (-5350 8000) $PN 2
R 1
J 2
(-5360 7990);
DISPLAY 0.680851 (-5360 7990);
PAINT MONO (-5360 7990);
FORCEPROP 1 LAST VALUE 4.7KOHM
J 0
(-5300 8200);
DISPLAY 0.978723 (-5300 8200);
PAINT GREEN (-5300 8200);
FORCEPROP 0 LAST PACKAGE 0402
J 0
(-5300 8300);
DISPLAY 1.021277 (-5300 8300);
FORCEPROP 1 LAST PATH I16
J 0
(-5547 8255);
DISPLAY 1.212766 (-5547 8255);
PAINT GREEN (-5547 8255);
DISPLAY INVISIBLE (-5547 8255);
FORCEPROP 1 LAST TOLERANCE 1%
J 0
(-5547 8405);
DISPLAY 1.212766 (-5547 8405);
PAINT GREEN (-5547 8405);
DISPLAY INVISIBLE (-5547 8405);
FORCEPROP 1 LAST CLS_PN G155-14701-01
J 0
(-5486 8350);
DISPLAY 1.212766 (-5486 8350);
PAINT GREEN (-5486 8350);
DISPLAY INVISIBLE (-5486 8350);
FORCEPROP 2 LAST CDS_LIB passive
J 0
(-5350 8150);
DISPLAY INVISIBLE (-5350 8150);
FORCEPROP 1 LAST CDS_LMAN_SYM_OUTLINE -50,50,50,-100
J 0
(-5350 8150);
DISPLAY 0.468085 (-5350 8150);
PAINT GREEN (-5350 8150);
DISPLAY INVISIBLE (-5350 8150);
FORCEADD GND_SG..1
(-3900 6450);
FORCEPROP 3 LASTPIN (-3850 6500) SIG_NAME SG\g
J 0
(-3840 6510);
DISPLAY 0.659574 (-3840 6510);
PAINT MONO (-3840 6510);
DISPLAY INVISIBLE (-3840 6510);
FORCEPROP 1 LAST HDL_POWER SG
J 1
(-3845 6355);
DISPLAY 0.808511 (-3845 6355);
PAINT GREEN (-3845 6355);
FORCEPROP 1 LAST PATH I29
J 0
(-3865 6450);
DISPLAY 0.808511 (-3865 6450);
PAINT GREEN (-3865 6450);
DISPLAY INVISIBLE (-3865 6450);
FORCEPROP 1 LAST BODY_TYPE PLUMBING
J 0
(-3885 6435);
DISPLAY 0.808511 (-3885 6435);
PAINT GREEN (-3885 6435);
DISPLAY INVISIBLE (-3885 6435);
FORCEPROP 1 LAST CDS_LMAN_SYM_OUTLINE 0,0,100,-50
J 0
(-3900 6450);
DISPLAY 0.468085 (-3900 6450);
PAINT GREEN (-3900 6450);
DISPLAY INVISIBLE (-3900 6450);
FORCEPROP 2 LAST CDS_LIB cls
J 0
(-3900 6450);
PAINT MONO (-3900 6450);
DISPLAY INVISIBLE (-3900 6450);
FORCEADD RESISTOR..2
(-3850 6900);
FORCEPROP 1 LAST $LOCATION R334
J 0
(-3800 6750);
DISPLAY 1.212766 (-3800 6750);
PAINT GREEN (-3800 6750);
FORCEPROP 0 LAST CDS_LOCATION R334
J 0
(-3800 6750);
DISPLAY 1.212766 (-3800 6750);
PAINT GREEN (-3800 6750);
DISPLAY INVISIBLE (-3800 6750);
FORCEPROP 2 LAST $SEC 1
J 0
(-4015 7085);
DISPLAY 0.680851 (-4015 7085);
PAINT MONO (-4015 7085);
DISPLAY INVISIBLE (-4015 7085);
FORCEPROP 2 LAST CDS_SEC 1
J 0
(-4015 7085);
DISPLAY 1.021277 (-4015 7085);
DISPLAY INVISIBLE (-4015 7085);
FORCEPROP 2 LASTPIN (-3850 7000) $PN 1
R 1
J 0
(-3860 7010);
DISPLAY 0.808511 (-3860 7010);
FORCEPROP 2 LASTPIN (-3850 6750) $PN 2
R 1
J 2
(-3860 6740);
DISPLAY 0.808511 (-3860 6740);
FORCEPROP 0 LAST PACKAGE 0402
J 0
(-3800 7100);
DISPLAY 1.021277 (-3800 7100);
FORCEPROP 1 LAST VALUE 1KOHM
J 0
(-3800 6950);
DISPLAY 1.212766 (-3800 6950);
PAINT GREEN (-3800 6950);
FORCEPROP 1 LAST PATH I30
J 0
(-4047 7005);
DISPLAY 1.212766 (-4047 7005);
PAINT GREEN (-4047 7005);
DISPLAY INVISIBLE (-4047 7005);
FORCEPROP 1 LAST TOLERANCE 1%
J 0
(-4047 7155);
DISPLAY 1.212766 (-4047 7155);
PAINT GREEN (-4047 7155);
DISPLAY INVISIBLE (-4047 7155);
FORCEPROP 1 LAST CLS_PN G155-11001-01
J 0
(-3986 7100);
DISPLAY 1.212766 (-3986 7100);
PAINT GREEN (-3986 7100);
DISPLAY INVISIBLE (-3986 7100);
FORCEPROP 2 LAST CDS_LIB passive
J 0
(-3850 6900);
PAINT MONO (-3850 6900);
DISPLAY INVISIBLE (-3850 6900);
FORCEPROP 1 LAST CDS_LMAN_SYM_OUTLINE -50,50,50,-100
J 0
(-3850 6900);
DISPLAY 0.468085 (-3850 6900);
PAINT GREEN (-3850 6900);
DISPLAY INVISIBLE (-3850 6900);
FORCEADD RESISTOR..2
(-3850 8150);
FORCEPROP 1 LAST $LOCATION R333
J 0
(-3800 8000);
DISPLAY 1.212766 (-3800 8000);
PAINT GREEN (-3800 8000);
FORCEPROP 0 LAST CDS_LOCATION R333
J 0
(-3800 8000);
DISPLAY 1.212766 (-3800 8000);
PAINT GREEN (-3800 8000);
DISPLAY INVISIBLE (-3800 8000);
FORCEPROP 2 LAST $SEC 1
J 0
(-3765 8385);
DISPLAY 0.680851 (-3765 8385);
PAINT MONO (-3765 8385);
DISPLAY INVISIBLE (-3765 8385);
FORCEPROP 2 LAST CDS_SEC 1
J 0
(-3765 8385);
DISPLAY 1.021277 (-3765 8385);
DISPLAY INVISIBLE (-3765 8385);
FORCEPROP 2 LASTPIN (-3850 8250) $PN 1
R 1
J 0
(-3860 8260);
DISPLAY 0.808511 (-3860 8260);
FORCEPROP 2 LASTPIN (-3850 8000) $PN 2
R 1
J 2
(-3860 7990);
DISPLAY 0.808511 (-3860 7990);
FORCEPROP 0 LAST NO_ASSY TRUE
J 0
(-4000 8100);
DISPLAY 0.808511 (-4000 8100);
DISPLAY BOTH (-4000 8100);
FORCEPROP 1 LAST VALUE 4.7KOHM
J 0
(-3800 8200);
DISPLAY 0.978723 (-3800 8200);
PAINT GREEN (-3800 8200);
FORCEPROP 0 LAST PACKAGE 0402
J 0
(-3800 8300);
DISPLAY 1.021277 (-3800 8300);
FORCEPROP 1 LAST PATH I31
J 0
(-4047 8255);
DISPLAY 1.212766 (-4047 8255);
PAINT GREEN (-4047 8255);
DISPLAY INVISIBLE (-4047 8255);
FORCEPROP 1 LAST TOLERANCE 1%
J 0
(-4047 8405);
DISPLAY 1.212766 (-4047 8405);
PAINT GREEN (-4047 8405);
DISPLAY INVISIBLE (-4047 8405);
FORCEPROP 1 LAST CLS_PN G155-14701-01
J 0
(-3986 8350);
DISPLAY 1.212766 (-3986 8350);
PAINT GREEN (-3986 8350);
DISPLAY INVISIBLE (-3986 8350);
FORCEPROP 2 LAST CDS_LIB passive
J 0
(-3850 8150);
PAINT MONO (-3850 8150);
DISPLAY INVISIBLE (-3850 8150);
FORCEPROP 1 LAST CDS_LMAN_SYM_OUTLINE -50,50,50,-100
J 0
(-3850 8150);
DISPLAY 0.468085 (-3850 8150);
PAINT GREEN (-3850 8150);
DISPLAY INVISIBLE (-3850 8150);
FORCEADD RESISTOR..2
(-3400 6900);
FORCEPROP 1 LAST $LOCATION R336
J 0
(-3350 6750);
DISPLAY 1.212766 (-3350 6750);
PAINT GREEN (-3350 6750);
FORCEPROP 0 LAST CDS_LOCATION R336
J 0
(-3350 6750);
DISPLAY 1.212766 (-3350 6750);
PAINT GREEN (-3350 6750);
DISPLAY INVISIBLE (-3350 6750);
FORCEPROP 2 LAST $SEC 1
J 0
(-3560 7075);
DISPLAY 0.680851 (-3560 7075);
PAINT MONO (-3560 7075);
DISPLAY INVISIBLE (-3560 7075);
FORCEPROP 2 LAST CDS_SEC 1
J 0
(-3560 7075);
DISPLAY 1.021277 (-3560 7075);
DISPLAY INVISIBLE (-3560 7075);
FORCEPROP 2 LASTPIN (-3400 7000) $PN 1
R 1
J 0
(-3410 7010);
DISPLAY 0.808511 (-3410 7010);
FORCEPROP 2 LASTPIN (-3400 6750) $PN 2
R 1
J 2
(-3410 6740);
DISPLAY 0.808511 (-3410 6740);
FORCEPROP 1 LAST VALUE 1KOHM
J 0
(-3350 6950);
DISPLAY 1.212766 (-3350 6950);
PAINT GREEN (-3350 6950);
FORCEPROP 0 LAST PACKAGE 0402
J 0
(-3350 7100);
DISPLAY 1.021277 (-3350 7100);
FORCEPROP 1 LAST PATH I32
J 0
(-3597 7005);
DISPLAY 1.212766 (-3597 7005);
PAINT GREEN (-3597 7005);
DISPLAY INVISIBLE (-3597 7005);
FORCEPROP 1 LAST TOLERANCE 1%
J 0
(-3597 7155);
DISPLAY 1.212766 (-3597 7155);
PAINT GREEN (-3597 7155);
DISPLAY INVISIBLE (-3597 7155);
FORCEPROP 1 LAST CLS_PN G155-11001-01
J 0
(-3536 7100);
DISPLAY 1.212766 (-3536 7100);
PAINT GREEN (-3536 7100);
DISPLAY INVISIBLE (-3536 7100);
FORCEPROP 2 LAST CDS_LIB passive
J 0
(-3400 6900);
PAINT MONO (-3400 6900);
DISPLAY INVISIBLE (-3400 6900);
FORCEPROP 1 LAST CDS_LMAN_SYM_OUTLINE -50,50,50,-100
J 0
(-3400 6900);
DISPLAY 0.468085 (-3400 6900);
PAINT GREEN (-3400 6900);
DISPLAY INVISIBLE (-3400 6900);
FORCEADD RESISTOR..2
(-3020 6890);
FORCEPROP 1 LAST $LOCATION R338
J 0
(-2970 6740);
DISPLAY 1.212766 (-2970 6740);
PAINT GREEN (-2970 6740);
FORCEPROP 0 LAST CDS_LOCATION R338
J 0
(-2970 6740);
DISPLAY 1.212766 (-2970 6740);
PAINT GREEN (-2970 6740);
DISPLAY INVISIBLE (-2970 6740);
FORCEPROP 2 LAST $SEC 1
J 0
(-3215 7070);
DISPLAY 0.680851 (-3215 7070);
PAINT MONO (-3215 7070);
DISPLAY INVISIBLE (-3215 7070);
FORCEPROP 2 LAST CDS_SEC 1
J 0
(-3215 7070);
DISPLAY 1.021277 (-3215 7070);
DISPLAY INVISIBLE (-3215 7070);
FORCEPROP 2 LASTPIN (-3020 6990) $PN 1
R 1
J 0
(-3030 7000);
DISPLAY 0.808511 (-3030 7000);
FORCEPROP 2 LASTPIN (-3020 6740) $PN 2
R 1
J 2
(-3030 6730);
DISPLAY 0.808511 (-3030 6730);
FORCEPROP 1 LAST VALUE 1KOHM
J 0
(-2950 6900);
DISPLAY 1.212766 (-2950 6900);
PAINT GREEN (-2950 6900);
FORCEPROP 0 LAST PACKAGE 0402
J 0
(-2950 7050);
DISPLAY 1.021277 (-2950 7050);
FORCEPROP 1 LAST PATH I33
J 0
(-3217 6995);
DISPLAY 1.212766 (-3217 6995);
PAINT GREEN (-3217 6995);
DISPLAY INVISIBLE (-3217 6995);
FORCEPROP 1 LAST TOLERANCE 1%
J 0
(-3217 7145);
DISPLAY 1.212766 (-3217 7145);
PAINT GREEN (-3217 7145);
DISPLAY INVISIBLE (-3217 7145);
FORCEPROP 1 LAST CLS_PN G155-11001-01
J 0
(-3156 7090);
DISPLAY 1.212766 (-3156 7090);
PAINT GREEN (-3156 7090);
DISPLAY INVISIBLE (-3156 7090);
FORCEPROP 1 LAST CDS_LMAN_SYM_OUTLINE -50,50,50,-100
J 0
(-3020 6890);
DISPLAY 0.468085 (-3020 6890);
PAINT GREEN (-3020 6890);
DISPLAY INVISIBLE (-3020 6890);
FORCEPROP 2 LAST CDS_LIB passive
J 0
(-3020 6890);
PAINT MONO (-3020 6890);
DISPLAY INVISIBLE (-3020 6890);
FORCEADD LM75BDP_TSSOP8..1
(-2700 7800);
FORCEPROP 1 LAST $LOCATION U8
J 0
(-2700 7800);
DISPLAY 1.212766 (-2700 7800);
PAINT GREEN (-2700 7800);
FORCEPROP 0 LAST CDS_LOCATION U8
J 0
(-2700 8000);
DISPLAY 1.021277 (-2700 8000);
DISPLAY INVISIBLE (-2700 8000);
FORCEPROP 0 LAST $SEC 1
J 0
(-2700 8000);
DISPLAY 0.680851 (-2700 8000);
PAINT MONO (-2700 8000);
DISPLAY INVISIBLE (-2700 8000);
FORCEPROP 0 LAST CDS_SEC 1
J 0
(-2700 8000);
DISPLAY 1.021277 (-2700 8000);
DISPLAY INVISIBLE (-2700 8000);
FORCEPROP 0 LASTPIN (-2800 7200) $PN 7
J 2
(-2810 7210);
DISPLAY 0.680851 (-2810 7210);
PAINT MONO (-2810 7210);
FORCEPROP 0 LASTPIN (-2800 7300) $PN 6
J 2
(-2810 7310);
DISPLAY 0.680851 (-2810 7310);
PAINT MONO (-2810 7310);
FORCEPROP 0 LASTPIN (-2800 7400) $PN 5
J 2
(-2810 7410);
DISPLAY 0.680851 (-2810 7410);
PAINT MONO (-2810 7410);
FORCEPROP 0 LASTPIN (-2100 7500) $PN 3
J 0
(-2090 7510);
DISPLAY 0.680851 (-2090 7510);
PAINT MONO (-2090 7510);
FORCEPROP 0 LASTPIN (-2800 7700) $PN 2
J 2
(-2810 7710);
DISPLAY 0.680851 (-2810 7710);
PAINT MONO (-2810 7710);
FORCEPROP 0 LASTPIN (-2800 7600) $PN 1
J 2
(-2810 7610);
DISPLAY 0.680851 (-2810 7610);
PAINT MONO (-2810 7610);
FORCEPROP 0 LAST PART_NUMBER LM75BDP,118
J 0
(-2700 8000);
DISPLAY 1.021277 (-2700 8000);
FORCEPROP 1 LAST CLS_PN G220-10215-01
J 0
(-2700 7900);
DISPLAY 1.212766 (-2700 7900);
PAINT GREEN (-2700 7900);
FORCEPROP 1 LAST PATH I34
J 0
(-2650 7850);
DISPLAY 1.212766 (-2650 7850);
PAINT GREEN (-2650 7850);
DISPLAY INVISIBLE (-2650 7850);
FORCEPROP 2 LASTPIN (-2800 7400) SIG_NAME UN$6$LM75BDPTSSOP8$I34$A2
J 0
(-2790 7410);
DISPLAY 0.659574 (-2790 7410);
PAINT MONO (-2790 7410);
DISPLAY INVISIBLE (-2790 7410);
FORCEPROP 2 LASTPIN (-2800 7300) SIG_NAME UN$6$LM75BDPTSSOP8$I34$A1
J 0
(-2790 7310);
DISPLAY 0.659574 (-2790 7310);
PAINT MONO (-2790 7310);
DISPLAY INVISIBLE (-2790 7310);
FORCEPROP 2 LASTPIN (-2800 7200) SIG_NAME UN$6$LM75BDPTSSOP8$I34$A0
J 0
(-2790 7210);
DISPLAY 0.659574 (-2790 7210);
PAINT MONO (-2790 7210);
DISPLAY INVISIBLE (-2790 7210);
FORCEPROP 1 LAST CDS_LMAN_SYM_OUTLINE 0,0,500,-800
J 0
(-2700 7800);
DISPLAY 0.468085 (-2700 7800);
PAINT GREEN (-2700 7800);
DISPLAY INVISIBLE (-2700 7800);
FORCEPROP 2 LAST CDS_LIB interface
J 0
(-2700 7800);
DISPLAY INVISIBLE (-2700 7800);
FORCEADD RESISTOR..2
(-3400 8150);
FORCEPROP 1 LAST $LOCATION R335
J 0
(-3350 8000);
DISPLAY 1.212766 (-3350 8000);
PAINT GREEN (-3350 8000);
FORCEPROP 0 LAST CDS_LOCATION R335
J 0
(-3350 8000);
DISPLAY 1.212766 (-3350 8000);
PAINT GREEN (-3350 8000);
DISPLAY INVISIBLE (-3350 8000);
FORCEPROP 2 LAST $SEC 1
J 0
(-3310 8385);
DISPLAY 0.680851 (-3310 8385);
PAINT MONO (-3310 8385);
DISPLAY INVISIBLE (-3310 8385);
FORCEPROP 2 LAST CDS_SEC 1
J 0
(-3310 8385);
DISPLAY 1.021277 (-3310 8385);
DISPLAY INVISIBLE (-3310 8385);
FORCEPROP 2 LASTPIN (-3400 8250) $PN 1
R 1
J 0
(-3410 8260);
DISPLAY 0.808511 (-3410 8260);
FORCEPROP 2 LASTPIN (-3400 8000) $PN 2
R 1
J 2
(-3410 7990);
DISPLAY 0.808511 (-3410 7990);
FORCEPROP 1 LAST VALUE 4.7KOHM
J 0
(-3350 8200);
DISPLAY 0.978723 (-3350 8200);
PAINT GREEN (-3350 8200);
FORCEPROP 0 LAST NO_ASSY TRUE
J 0
(-3500 8100);
DISPLAY 0.808511 (-3500 8100);
DISPLAY BOTH (-3500 8100);
FORCEPROP 0 LAST PACKAGE 0402
J 0
(-3350 8300);
DISPLAY 1.021277 (-3350 8300);
FORCEPROP 1 LAST PATH I35
J 0
(-3597 8255);
DISPLAY 1.212766 (-3597 8255);
PAINT GREEN (-3597 8255);
DISPLAY INVISIBLE (-3597 8255);
FORCEPROP 1 LAST TOLERANCE 1%
J 0
(-3597 8405);
DISPLAY 1.212766 (-3597 8405);
PAINT GREEN (-3597 8405);
DISPLAY INVISIBLE (-3597 8405);
FORCEPROP 1 LAST CLS_PN G155-14701-01
J 0
(-3536 8350);
DISPLAY 1.212766 (-3536 8350);
PAINT GREEN (-3536 8350);
DISPLAY INVISIBLE (-3536 8350);
FORCEPROP 2 LAST CDS_LIB passive
J 0
(-3400 8150);
PAINT MONO (-3400 8150);
DISPLAY INVISIBLE (-3400 8150);
FORCEPROP 1 LAST CDS_LMAN_SYM_OUTLINE -50,50,50,-100
J 0
(-3400 8150);
DISPLAY 0.468085 (-3400 8150);
PAINT GREEN (-3400 8150);
DISPLAY INVISIBLE (-3400 8150);
FORCEADD RESISTOR..2
(-3000 8150);
FORCEPROP 1 LAST $LOCATION R337
J 0
(-2950 8000);
DISPLAY 1.212766 (-2950 8000);
PAINT GREEN (-2950 8000);
FORCEPROP 0 LAST CDS_LOCATION R337
J 0
(-2950 8000);
DISPLAY 1.212766 (-2950 8000);
PAINT GREEN (-2950 8000);
DISPLAY INVISIBLE (-2950 8000);
FORCEPROP 2 LAST $SEC 1
J 0
(-2895 8370);
DISPLAY 0.680851 (-2895 8370);
PAINT MONO (-2895 8370);
DISPLAY INVISIBLE (-2895 8370);
FORCEPROP 2 LAST CDS_SEC 1
J 0
(-2895 8370);
DISPLAY 1.021277 (-2895 8370);
DISPLAY INVISIBLE (-2895 8370);
FORCEPROP 2 LASTPIN (-3000 8250) $PN 1
R 1
J 0
(-3010 8260);
DISPLAY 0.808511 (-3010 8260);
FORCEPROP 2 LASTPIN (-3000 8000) $PN 2
R 1
J 2
(-3010 7990);
DISPLAY 0.808511 (-3010 7990);
FORCEPROP 1 LAST VALUE 4.7KOHM
J 0
(-2950 8200);
DISPLAY 0.978723 (-2950 8200);
PAINT GREEN (-2950 8200);
FORCEPROP 0 LAST PACKAGE 0402
J 0
(-2950 8300);
DISPLAY 1.021277 (-2950 8300);
FORCEPROP 0 LAST NO_ASSY TRUE
J 0
(-2950 8100);
DISPLAY 0.808511 (-2950 8100);
DISPLAY BOTH (-2950 8100);
FORCEPROP 1 LAST PATH I36
J 0
(-3197 8255);
DISPLAY 1.212766 (-3197 8255);
PAINT GREEN (-3197 8255);
DISPLAY INVISIBLE (-3197 8255);
FORCEPROP 1 LAST TOLERANCE 1%
J 0
(-3197 8405);
DISPLAY 1.212766 (-3197 8405);
PAINT GREEN (-3197 8405);
DISPLAY INVISIBLE (-3197 8405);
FORCEPROP 1 LAST CLS_PN G155-14701-01
J 0
(-3136 8350);
DISPLAY 1.212766 (-3136 8350);
PAINT GREEN (-3136 8350);
DISPLAY INVISIBLE (-3136 8350);
FORCEPROP 1 LAST CDS_LMAN_SYM_OUTLINE -50,50,50,-100
J 0
(-3000 8150);
DISPLAY 0.468085 (-3000 8150);
PAINT GREEN (-3000 8150);
DISPLAY INVISIBLE (-3000 8150);
FORCEPROP 2 LAST CDS_LIB passive
J 0
(-3000 8150);
PAINT MONO (-3000 8150);
DISPLAY INVISIBLE (-3000 8150);
FORCEADD CAPACITOR..1
(-1450 6400);
FORCEPROP 1 LAST $LOCATION C39
J 2
(-1650 6400);
DISPLAY 1.212766 (-1650 6400);
PAINT GREEN (-1650 6400);
FORCEPROP 0 LAST CDS_LOCATION C39
J 0
(-1200 6500);
DISPLAY 1.021277 (-1200 6500);
DISPLAY INVISIBLE (-1200 6500);
FORCEPROP 0 LAST $SEC 1
J 0
(-1200 6500);
DISPLAY 0.680851 (-1200 6500);
PAINT MONO (-1200 6500);
DISPLAY INVISIBLE (-1200 6500);
FORCEPROP 0 LAST CDS_SEC 1
J 0
(-1200 6500);
DISPLAY 1.021277 (-1200 6500);
DISPLAY INVISIBLE (-1200 6500);
FORCEPROP 0 LASTPIN (-1550 6400) $PN 1
J 2
(-1560 6410);
DISPLAY 0.680851 (-1560 6410);
PAINT MONO (-1560 6410);
FORCEPROP 0 LASTPIN (-1300 6400) $PN 2
J 0
(-1290 6410);
DISPLAY 0.680851 (-1290 6410);
PAINT MONO (-1290 6410);
FORCEPROP 0 LAST PACKAGE 0402
J 0
(-1500 6500);
DISPLAY 1.021277 (-1500 6500);
FORCEPROP 0 LAST VOLTAGE 25V
J 0
(-1500 6600);
DISPLAY 1.021277 (-1500 6600);
FORCEPROP 1 LAST VALUE 0.1UF
J 0
(-1200 6400);
DISPLAY 1.212766 (-1200 6400);
PAINT GREEN (-1200 6400);
FORCEPROP 1 LAST PATH I37
J 2
(-1500 6500);
DISPLAY 1.212766 (-1500 6500);
PAINT GREEN (-1500 6500);
DISPLAY INVISIBLE (-1500 6500);
FORCEPROP 1 LAST CLS_PN G105-0B104-EK
J 2
(-1500 6500);
DISPLAY 1.212766 (-1500 6500);
PAINT GREEN (-1500 6500);
DISPLAY INVISIBLE (-1500 6500);
FORCEPROP 1 LAST CDS_LMAN_SYM_OUTLINE 0,50,50,-50
J 0
(-1450 6400);
DISPLAY 0.468085 (-1450 6400);
PAINT GREEN (-1450 6400);
DISPLAY INVISIBLE (-1450 6400);
FORCEPROP 2 LAST CDS_LIB passive
J 0
(-1450 6400);
DISPLAY INVISIBLE (-1450 6400);
FORCEPROP 1 LAST TOLERANCE 10%
J 2
(-1550 6500);
DISPLAY 1.212766 (-1550 6500);
PAINT GREEN (-1550 6500);
DISPLAY INVISIBLE (-1550 6500);
FORCEADD LM75BDP_TSSOP8..2
R 5
(-1050 7100);
FORCEPROP 1 LAST $LOCATION U8
J 2
(-1650 7250);
DISPLAY 1.212766 (-1650 7250);
PAINT GREEN (-1650 7250);
FORCEPROP 0 LAST CDS_LOCATION U8
J 0
(-1650 7350);
DISPLAY 1.021277 (-1650 7350);
DISPLAY INVISIBLE (-1650 7350);
FORCEPROP 0 LAST $SEC 2
J 0
(-1650 7350);
DISPLAY 0.680851 (-1650 7350);
PAINT MONO (-1650 7350);
DISPLAY INVISIBLE (-1650 7350);
FORCEPROP 0 LAST CDS_SEC 2
J 0
(-1650 7350);
DISPLAY 1.021277 (-1650 7350);
DISPLAY INVISIBLE (-1650 7350);
FORCEPROP 0 LASTPIN (-1850 6900) $PN 4
J 2
(-1860 6910);
DISPLAY 0.680851 (-1860 6910);
PAINT MONO (-1860 6910);
FORCEPROP 0 LASTPIN (-950 6900) $PN 8
J 0
(-940 6910);
DISPLAY 0.680851 (-940 6910);
PAINT MONO (-940 6910);
FORCEPROP 1 LAST CLS_PN G220-10215-01
J 2
(-1015 7155);
DISPLAY 1.212766 (-1015 7155);
PAINT GREEN (-1015 7155);
FORCEPROP 1 LAST PATH I38
R 3
J 2
(-1000 7150);
DISPLAY 1.212766 (-1000 7150);
PAINT GREEN (-1000 7150);
DISPLAY INVISIBLE (-1000 7150);
FORCEPROP 1 LAST CDS_LMAN_SYM_OUTLINE 0,0,400,-700
R 3
J 0
(-1050 7100);
DISPLAY 0.468085 (-1050 7100);
PAINT GREEN (-1050 7100);
DISPLAY INVISIBLE (-1050 7100);
FORCEPROP 2 LAST CDS_LIB interface
J 0
(-1050 7100);
DISPLAY INVISIBLE (-1050 7100);
FORCEADD RESISTOR..2
(-1350 7900);
FORCEPROP 1 LAST $LOCATION R340
J 0
(-1300 7750);
DISPLAY 1.212766 (-1300 7750);
PAINT GREEN (-1300 7750);
FORCEPROP 0 LAST CDS_LOCATION R340
J 0
(-1300 7750);
DISPLAY 1.212766 (-1300 7750);
PAINT GREEN (-1300 7750);
DISPLAY INVISIBLE (-1300 7750);
FORCEPROP 2 LAST $SEC 1
J 0
(-1245 8120);
DISPLAY 0.680851 (-1245 8120);
PAINT MONO (-1245 8120);
DISPLAY INVISIBLE (-1245 8120);
FORCEPROP 2 LAST CDS_SEC 1
J 0
(-1245 8120);
DISPLAY 1.021277 (-1245 8120);
DISPLAY INVISIBLE (-1245 8120);
FORCEPROP 2 LASTPIN (-1350 8000) $PN 1
R 1
J 0
(-1360 8010);
DISPLAY 0.808511 (-1360 8010);
FORCEPROP 2 LASTPIN (-1350 7750) $PN 2
R 1
J 2
(-1360 7740);
DISPLAY 0.808511 (-1360 7740);
FORCEPROP 0 LAST PACKAGE 0402
J 0
(-1300 7850);
DISPLAY 1.021277 (-1300 7850);
FORCEPROP 1 LAST VALUE 4.7KOHM
J 0
(-1300 7950);
DISPLAY 1.212766 (-1300 7950);
PAINT GREEN (-1300 7950);
FORCEPROP 2 LAST CDS_LIB passive
J 0
(-1350 7900);
PAINT MONO (-1350 7900);
DISPLAY INVISIBLE (-1350 7900);
FORCEPROP 1 LAST CDS_LMAN_SYM_OUTLINE -50,50,50,-100
J 0
(-1350 7900);
DISPLAY 0.468085 (-1350 7900);
PAINT GREEN (-1350 7900);
DISPLAY INVISIBLE (-1350 7900);
FORCEPROP 1 LAST CLS_PN G155-14701-01
J 0
(-1486 8100);
DISPLAY 1.212766 (-1486 8100);
PAINT GREEN (-1486 8100);
DISPLAY INVISIBLE (-1486 8100);
FORCEPROP 1 LAST TOLERANCE 1%
J 0
(-1547 8155);
DISPLAY 1.212766 (-1547 8155);
PAINT GREEN (-1547 8155);
DISPLAY INVISIBLE (-1547 8155);
FORCEPROP 1 LAST PATH I41
J 0
(-1547 8005);
DISPLAY 1.212766 (-1547 8005);
PAINT GREEN (-1547 8005);
DISPLAY INVISIBLE (-1547 8005);
FORCEADD OFFPAGE_OUT..1
(150 7500);
FORCEPROP 1 LAST CDS_LMAN_SYM_OUTLINE -50,50,50,-50
J 0
(150 7500);
DISPLAY 0.468085 (150 7500);
PAINT GREEN (150 7500);
DISPLAY INVISIBLE (150 7500);
FORCEPROP 2 LAST CDS_LIB cls
J 0
(150 7500);
PAINT MONO (150 7500);
DISPLAY INVISIBLE (150 7500);
FORCEPROP 1 LAST BODY_TYPE COMMENT
J 0
(160 7635);
DISPLAY 0.808511 (160 7635);
PAINT GREEN (160 7635);
DISPLAY INVISIBLE (160 7635);
FORCEPROP 1 LAST OFFPAGE TRUE
J 0
(160 7555);
DISPLAY 0.808511 (160 7555);
PAINT GREEN (160 7555);
DISPLAY INVISIBLE (160 7555);
FORCEPROP 2 LAST PATH I44
J 0
(200 7600);
DISPLAY 1.021277 (200 7600);
DISPLAY INVISIBLE (200 7600);
FORCEPROP 2 LAST $XR1 12F5< 
J 0
(415 7500);
DISPLAY 0.638298 (415 7500);
PAINT MONO (415 7500);
FORCEPROP 2 LAST $XR0 25D6<> 
J 0
(205 7500);
DISPLAY 0.638298 (205 7500);
PAINT MONO (205 7500);
FORCEADD GND_SG..1
(-2100 6150);
FORCEPROP 3 LASTPIN (-2050 6200) SIG_NAME SG\g
J 0
(-2040 6210);
DISPLAY 0.659574 (-2040 6210);
PAINT MONO (-2040 6210);
DISPLAY INVISIBLE (-2040 6210);
FORCEPROP 1 LAST HDL_POWER SG
J 1
(-2045 6055);
DISPLAY 0.808511 (-2045 6055);
PAINT GREEN (-2045 6055);
FORCEPROP 1 LAST PATH I45
J 0
(-2065 6150);
DISPLAY 0.808511 (-2065 6150);
PAINT GREEN (-2065 6150);
DISPLAY INVISIBLE (-2065 6150);
FORCEPROP 1 LAST BODY_TYPE PLUMBING
J 0
(-2085 6135);
DISPLAY 0.808511 (-2085 6135);
PAINT GREEN (-2085 6135);
DISPLAY INVISIBLE (-2085 6135);
FORCEPROP 1 LAST CDS_LMAN_SYM_OUTLINE 0,0,100,-50
J 0
(-2100 6150);
DISPLAY 0.468085 (-2100 6150);
PAINT GREEN (-2100 6150);
DISPLAY INVISIBLE (-2100 6150);
FORCEPROP 2 LAST CDS_LIB cls
J 0
(-2100 6150);
PAINT MONO (-2100 6150);
DISPLAY INVISIBLE (-2100 6150);
FORCEADD VCC..1
(-5950 8550);
FORCEPROP 3 LASTPIN (-5900 8500) SIG_NAME XP3R3V_FPGA\g
J 0
(-5890 8510);
DISPLAY 0.659574 (-5890 8510);
PAINT MONO (-5890 8510);
DISPLAY INVISIBLE (-5890 8510);
FORCEPROP 1 LAST HDL_POWER XP3R3V_FPGA
J 1
(-5895 8605);
DISPLAY 1.021277 (-5895 8605);
PAINT GREEN (-5895 8605);
FORCEPROP 0 LAST VOLTAGE 3.3V
J 0
(-6200 8700);
DISPLAY 1.021277 (-6200 8700);
DISPLAY BOTH (-6200 8700);
FORCEPROP 1 LAST PATH I56
J 0
(-5915 8640);
DISPLAY 0.808511 (-5915 8640);
PAINT GREEN (-5915 8640);
DISPLAY INVISIBLE (-5915 8640);
FORCEPROP 1 LAST BODY_TYPE PLUMBING
J 0
(-5995 8507);
DISPLAY 0.340426 (-5995 8507);
PAINT GREEN (-5995 8507);
DISPLAY INVISIBLE (-5995 8507);
FORCEPROP 2 LAST CDS_LIB cls
J 0
(-5950 8550);
DISPLAY INVISIBLE (-5950 8550);
FORCEPROP 1 LAST CDS_LMAN_SYM_OUTLINE -250,250,250,-250
J 0
(-5950 8550);
DISPLAY 0.468085 (-5950 8550);
PAINT GREEN (-5950 8550);
DISPLAY INVISIBLE (-5950 8550);
FORCEADD VCC..1
(-1400 8150);
FORCEPROP 3 LASTPIN (-1350 8100) SIG_NAME XP3R3V_FPGA\g
J 0
(-1340 8110);
DISPLAY 0.659574 (-1340 8110);
PAINT MONO (-1340 8110);
DISPLAY INVISIBLE (-1340 8110);
FORCEPROP 1 LAST HDL_POWER XP3R3V_FPGA
J 1
(-1345 8205);
DISPLAY 1.021277 (-1345 8205);
PAINT GREEN (-1345 8205);
FORCEPROP 0 LAST VOLTAGE 3.3V
J 0
(-1650 8300);
DISPLAY 1.021277 (-1650 8300);
DISPLAY BOTH (-1650 8300);
FORCEPROP 1 LAST CDS_LMAN_SYM_OUTLINE -250,250,250,-250
J 0
(-1400 8150);
DISPLAY 0.468085 (-1400 8150);
PAINT GREEN (-1400 8150);
DISPLAY INVISIBLE (-1400 8150);
FORCEPROP 2 LAST CDS_LIB cls
J 0
(-1400 8150);
DISPLAY INVISIBLE (-1400 8150);
FORCEPROP 1 LAST BODY_TYPE PLUMBING
J 0
(-1445 8107);
DISPLAY 0.340426 (-1445 8107);
PAINT GREEN (-1445 8107);
DISPLAY INVISIBLE (-1445 8107);
FORCEPROP 1 LAST PATH I57
J 0
(-1365 8240);
DISPLAY 0.808511 (-1365 8240);
PAINT GREEN (-1365 8240);
DISPLAY INVISIBLE (-1365 8240);
FORCEADD VCC..1
(-600 7050);
FORCEPROP 3 LASTPIN (-550 7000) SIG_NAME XP3R3V_FPGA\g
J 0
(-540 7010);
DISPLAY 0.659574 (-540 7010);
PAINT MONO (-540 7010);
DISPLAY INVISIBLE (-540 7010);
FORCEPROP 1 LAST HDL_POWER XP3R3V_FPGA
J 1
(-545 7105);
DISPLAY 1.021277 (-545 7105);
PAINT GREEN (-545 7105);
FORCEPROP 0 LAST VOLTAGE 3.3V
J 0
(-850 7200);
DISPLAY 1.021277 (-850 7200);
DISPLAY BOTH (-850 7200);
FORCEPROP 1 LAST PATH I58
J 0
(-565 7140);
DISPLAY 0.808511 (-565 7140);
PAINT GREEN (-565 7140);
DISPLAY INVISIBLE (-565 7140);
FORCEPROP 1 LAST BODY_TYPE PLUMBING
J 0
(-645 7007);
DISPLAY 0.340426 (-645 7007);
PAINT GREEN (-645 7007);
DISPLAY INVISIBLE (-645 7007);
FORCEPROP 2 LAST CDS_LIB cls
J 0
(-600 7050);
DISPLAY INVISIBLE (-600 7050);
FORCEPROP 1 LAST CDS_LMAN_SYM_OUTLINE -250,250,250,-250
J 0
(-600 7050);
DISPLAY 0.468085 (-600 7050);
PAINT GREEN (-600 7050);
DISPLAY INVISIBLE (-600 7050);
FORCEADD LM75BDP_TSSOP8..1
(-2700 4650);
FORCEPROP 1 LAST $LOCATION U35
J 0
(-2700 4800);
DISPLAY 1.212766 (-2700 4800);
PAINT GREEN (-2700 4800);
FORCEPROP 0 LAST CDS_LOCATION U35
J 0
(-2500 4900);
DISPLAY 1.021277 (-2500 4900);
DISPLAY INVISIBLE (-2500 4900);
FORCEPROP 0 LAST $SEC 1
J 0
(-2500 4900);
DISPLAY 0.680851 (-2500 4900);
PAINT MONO (-2500 4900);
DISPLAY INVISIBLE (-2500 4900);
FORCEPROP 0 LAST CDS_SEC 1
J 0
(-2500 4900);
DISPLAY 1.021277 (-2500 4900);
DISPLAY INVISIBLE (-2500 4900);
FORCEPROP 0 LASTPIN (-2800 4050) $PN 7
J 2
(-2810 4060);
DISPLAY 0.680851 (-2810 4060);
PAINT MONO (-2810 4060);
FORCEPROP 0 LASTPIN (-2800 4150) $PN 6
J 2
(-2810 4160);
DISPLAY 0.680851 (-2810 4160);
PAINT MONO (-2810 4160);
FORCEPROP 0 LASTPIN (-2800 4250) $PN 5
J 2
(-2810 4260);
DISPLAY 0.680851 (-2810 4260);
PAINT MONO (-2810 4260);
FORCEPROP 0 LASTPIN (-2100 4350) $PN 3
J 0
(-2090 4360);
DISPLAY 0.680851 (-2090 4360);
PAINT MONO (-2090 4360);
FORCEPROP 0 LASTPIN (-2800 4550) $PN 2
J 2
(-2810 4560);
DISPLAY 0.680851 (-2810 4560);
PAINT MONO (-2810 4560);
FORCEPROP 0 LASTPIN (-2800 4450) $PN 1
J 2
(-2810 4460);
DISPLAY 0.680851 (-2810 4460);
PAINT MONO (-2810 4460);
FORCEPROP 1 LAST CLS_PN G220-10215-01
J 0
(-2700 4700);
DISPLAY 1.212766 (-2700 4700);
PAINT GREEN (-2700 4700);
FORCEPROP 0 LAST PART_NUMBER LM75BDP,118
J 0
(-2500 4850);
DISPLAY 1.021277 (-2500 4850);
FORCEPROP 1 LAST PATH I59
J 0
(-2650 4700);
DISPLAY 1.212766 (-2650 4700);
PAINT GREEN (-2650 4700);
DISPLAY INVISIBLE (-2650 4700);
FORCEPROP 2 LASTPIN (-2800 4150) SIG_NAME UN$6$LM75BDPTSSOP8$I59$A1
J 0
(-2790 4160);
DISPLAY 0.659574 (-2790 4160);
PAINT MONO (-2790 4160);
DISPLAY INVISIBLE (-2790 4160);
FORCEPROP 2 LASTPIN (-2800 4050) SIG_NAME UN$6$LM75BDPTSSOP8$I59$A0
J 0
(-2790 4060);
DISPLAY 0.659574 (-2790 4060);
PAINT MONO (-2790 4060);
DISPLAY INVISIBLE (-2790 4060);
FORCEPROP 2 LASTPIN (-2800 4250) SIG_NAME UN$6$LM75BDPTSSOP8$I59$A2
J 0
(-2790 4260);
DISPLAY 0.659574 (-2790 4260);
PAINT MONO (-2790 4260);
DISPLAY INVISIBLE (-2790 4260);
FORCEPROP 1 LAST CDS_LMAN_SYM_OUTLINE 0,0,500,-800
J 0
(-2700 4650);
DISPLAY 0.468085 (-2700 4650);
PAINT GREEN (-2700 4650);
DISPLAY INVISIBLE (-2700 4650);
FORCEPROP 2 LAST CDS_LIB interface
J 0
(-2700 4650);
DISPLAY INVISIBLE (-2700 4650);
FORCEADD RESISTOR..2
(-3400 3750);
FORCEPROP 1 LAST $LOCATION R413
J 0
(-3350 3600);
DISPLAY 1.212766 (-3350 3600);
PAINT GREEN (-3350 3600);
FORCEPROP 0 LAST CDS_LOCATION R413
J 0
(-3350 4000);
DISPLAY 1.021277 (-3350 4000);
DISPLAY INVISIBLE (-3350 4000);
FORCEPROP 0 LAST $SEC 1
J 0
(-3350 4000);
DISPLAY 0.680851 (-3350 4000);
PAINT MONO (-3350 4000);
DISPLAY INVISIBLE (-3350 4000);
FORCEPROP 0 LAST CDS_SEC 1
J 0
(-3350 4000);
DISPLAY 1.021277 (-3350 4000);
DISPLAY INVISIBLE (-3350 4000);
FORCEPROP 0 LASTPIN (-3400 3850) $PN 1
R 1
J 0
(-3410 3860);
DISPLAY 0.680851 (-3410 3860);
PAINT MONO (-3410 3860);
FORCEPROP 0 LASTPIN (-3400 3600) $PN 2
R 1
J 2
(-3410 3590);
DISPLAY 0.680851 (-3410 3590);
PAINT MONO (-3410 3590);
FORCEPROP 1 LAST VALUE 1KOHM
J 0
(-3350 3800);
DISPLAY 1.212766 (-3350 3800);
PAINT GREEN (-3350 3800);
FORCEPROP 0 LAST PACKAGE 0402
J 0
(-3350 3950);
DISPLAY 1.021277 (-3350 3950);
FORCEPROP 1 LAST PATH I60
J 0
(-3597 3855);
DISPLAY 1.212766 (-3597 3855);
PAINT GREEN (-3597 3855);
DISPLAY INVISIBLE (-3597 3855);
FORCEPROP 1 LAST TOLERANCE 1%
J 0
(-3597 4005);
DISPLAY 1.212766 (-3597 4005);
PAINT GREEN (-3597 4005);
DISPLAY INVISIBLE (-3597 4005);
FORCEPROP 1 LAST CLS_PN G155-11001-01
J 0
(-3536 3950);
DISPLAY 1.212766 (-3536 3950);
PAINT GREEN (-3536 3950);
DISPLAY INVISIBLE (-3536 3950);
FORCEPROP 1 LAST CDS_LMAN_SYM_OUTLINE -50,50,50,-100
J 0
(-3400 3750);
DISPLAY 0.468085 (-3400 3750);
PAINT GREEN (-3400 3750);
DISPLAY INVISIBLE (-3400 3750);
FORCEPROP 2 LAST CDS_LIB passive
J 0
(-3400 3750);
DISPLAY INVISIBLE (-3400 3750);
FORCEADD OFFPAGE_OUT..1
(350 4350);
FORCEPROP 2 LAST PATH I61
J 0
(400 4450);
DISPLAY 1.021277 (400 4450);
DISPLAY INVISIBLE (400 4450);
FORCEPROP 1 LAST OFFPAGE TRUE
J 0
(360 4405);
DISPLAY 0.808511 (360 4405);
PAINT GREEN (360 4405);
DISPLAY INVISIBLE (360 4405);
FORCEPROP 2 LAST CDS_LIB cls
J 0
(350 4350);
DISPLAY INVISIBLE (350 4350);
FORCEPROP 1 LAST CDS_LMAN_SYM_OUTLINE -50,50,50,-50
J 0
(350 4350);
DISPLAY 0.468085 (350 4350);
PAINT GREEN (350 4350);
DISPLAY INVISIBLE (350 4350);
FORCEPROP 1 LAST BODY_TYPE COMMENT
J 0
(360 4485);
DISPLAY 0.808511 (360 4485);
PAINT GREEN (360 4485);
DISPLAY INVISIBLE (360 4485);
FORCEPROP 2 LAST $XR1 12G5< 
J 0
(615 4350);
DISPLAY 0.638298 (615 4350);
PAINT MONO (615 4350);
FORCEPROP 2 LAST $XR0 25D6<> 
J 0
(405 4350);
DISPLAY 0.638298 (405 4350);
PAINT MONO (405 4350);
FORCEADD VCC..1
(-1200 5000);
FORCEPROP 3 LASTPIN (-1150 4950) SIG_NAME XP3R3V_FPGA\g
J 0
(-1140 4960);
DISPLAY 0.659574 (-1140 4960);
PAINT MONO (-1140 4960);
DISPLAY INVISIBLE (-1140 4960);
FORCEPROP 1 LAST HDL_POWER XP3R3V_FPGA
J 1
(-1145 5055);
DISPLAY 1.021277 (-1145 5055);
PAINT GREEN (-1145 5055);
FORCEPROP 0 LAST VOLTAGE 3.3V
J 0
(-1450 5150);
DISPLAY 1.021277 (-1450 5150);
DISPLAY BOTH (-1450 5150);
FORCEPROP 1 LAST PATH I62
J 0
(-1165 5090);
DISPLAY 0.808511 (-1165 5090);
PAINT GREEN (-1165 5090);
DISPLAY INVISIBLE (-1165 5090);
FORCEPROP 1 LAST BODY_TYPE PLUMBING
J 0
(-1245 4957);
DISPLAY 0.340426 (-1245 4957);
PAINT GREEN (-1245 4957);
DISPLAY INVISIBLE (-1245 4957);
FORCEPROP 1 LAST CDS_LMAN_SYM_OUTLINE -250,250,250,-250
J 0
(-1200 5000);
DISPLAY 0.468085 (-1200 5000);
PAINT GREEN (-1200 5000);
DISPLAY INVISIBLE (-1200 5000);
FORCEPROP 2 LAST CDS_LIB cls
J 0
(-1200 5000);
DISPLAY INVISIBLE (-1200 5000);
FORCEADD VCC..1
(-600 3900);
FORCEPROP 3 LASTPIN (-550 3850) SIG_NAME XP3R3V_FPGA\g
J 0
(-540 3860);
DISPLAY 0.659574 (-540 3860);
PAINT MONO (-540 3860);
DISPLAY INVISIBLE (-540 3860);
FORCEPROP 0 LAST VOLTAGE 3.3V
J 0
(-850 4050);
DISPLAY 1.021277 (-850 4050);
DISPLAY BOTH (-850 4050);
FORCEPROP 1 LAST HDL_POWER XP3R3V_FPGA
J 1
(-545 3955);
DISPLAY 1.021277 (-545 3955);
PAINT GREEN (-545 3955);
FORCEPROP 1 LAST PATH I63
J 0
(-565 3990);
DISPLAY 0.808511 (-565 3990);
PAINT GREEN (-565 3990);
DISPLAY INVISIBLE (-565 3990);
FORCEPROP 1 LAST BODY_TYPE PLUMBING
J 0
(-645 3857);
DISPLAY 0.340426 (-645 3857);
PAINT GREEN (-645 3857);
DISPLAY INVISIBLE (-645 3857);
FORCEPROP 1 LAST CDS_LMAN_SYM_OUTLINE -250,250,250,-250
J 0
(-600 3900);
DISPLAY 0.468085 (-600 3900);
PAINT GREEN (-600 3900);
DISPLAY INVISIBLE (-600 3900);
FORCEPROP 2 LAST CDS_LIB cls
J 0
(-600 3900);
DISPLAY INVISIBLE (-600 3900);
FORCEADD RESISTOR..2
(-1150 4750);
FORCEPROP 1 LAST $LOCATION R422
J 0
(-1100 4600);
DISPLAY 1.212766 (-1100 4600);
PAINT GREEN (-1100 4600);
FORCEPROP 0 LAST CDS_LOCATION R422
J 0
(-1100 4900);
DISPLAY 1.021277 (-1100 4900);
DISPLAY INVISIBLE (-1100 4900);
FORCEPROP 0 LAST $SEC 1
J 0
(-1100 4900);
DISPLAY 0.680851 (-1100 4900);
PAINT MONO (-1100 4900);
DISPLAY INVISIBLE (-1100 4900);
FORCEPROP 0 LAST CDS_SEC 1
J 0
(-1100 4900);
DISPLAY 1.021277 (-1100 4900);
DISPLAY INVISIBLE (-1100 4900);
FORCEPROP 0 LASTPIN (-1150 4850) $PN 1
R 1
J 0
(-1160 4860);
DISPLAY 0.680851 (-1160 4860);
PAINT MONO (-1160 4860);
FORCEPROP 0 LASTPIN (-1150 4600) $PN 2
R 1
J 2
(-1160 4590);
DISPLAY 0.680851 (-1160 4590);
PAINT MONO (-1160 4590);
FORCEPROP 0 LAST PACKAGE 0402
J 0
(-1100 4700);
DISPLAY 1.021277 (-1100 4700);
FORCEPROP 1 LAST VALUE 4.7KOHM
J 0
(-1100 4800);
DISPLAY 1.212766 (-1100 4800);
PAINT GREEN (-1100 4800);
FORCEPROP 1 LAST PATH I64
J 0
(-1347 4855);
DISPLAY 1.212766 (-1347 4855);
PAINT GREEN (-1347 4855);
DISPLAY INVISIBLE (-1347 4855);
FORCEPROP 1 LAST TOLERANCE 1%
J 0
(-1347 5005);
DISPLAY 1.212766 (-1347 5005);
PAINT GREEN (-1347 5005);
DISPLAY INVISIBLE (-1347 5005);
FORCEPROP 1 LAST CLS_PN G155-14701-01
J 0
(-1286 4950);
DISPLAY 1.212766 (-1286 4950);
PAINT GREEN (-1286 4950);
DISPLAY INVISIBLE (-1286 4950);
FORCEPROP 1 LAST CDS_LMAN_SYM_OUTLINE -50,50,50,-100
J 0
(-1150 4750);
DISPLAY 0.468085 (-1150 4750);
PAINT GREEN (-1150 4750);
DISPLAY INVISIBLE (-1150 4750);
FORCEPROP 2 LAST CDS_LIB passive
J 0
(-1150 4750);
DISPLAY INVISIBLE (-1150 4750);
FORCEADD LM75BDP_TSSOP8..2
R 5
(-1050 3950);
FORCEPROP 1 LAST $LOCATION U36
J 2
(-1650 4100);
DISPLAY 1.212766 (-1650 4100);
PAINT GREEN (-1650 4100);
FORCEPROP 0 LAST CDS_LOCATION U36
J 0
(-1650 4200);
DISPLAY 1.021277 (-1650 4200);
DISPLAY INVISIBLE (-1650 4200);
FORCEPROP 0 LAST $SEC 2
J 0
(-1650 4200);
DISPLAY 0.680851 (-1650 4200);
PAINT MONO (-1650 4200);
DISPLAY INVISIBLE (-1650 4200);
FORCEPROP 0 LAST CDS_SEC 2
J 0
(-1650 4200);
DISPLAY 1.021277 (-1650 4200);
DISPLAY INVISIBLE (-1650 4200);
FORCEPROP 0 LASTPIN (-1850 3750) $PN 4
J 2
(-1860 3760);
DISPLAY 0.680851 (-1860 3760);
PAINT MONO (-1860 3760);
FORCEPROP 0 LASTPIN (-950 3750) $PN 8
J 0
(-940 3760);
DISPLAY 0.680851 (-940 3760);
PAINT MONO (-940 3760);
FORCEPROP 1 LAST CLS_PN G220-10215-01
J 2
(-1015 4005);
DISPLAY 1.212766 (-1015 4005);
PAINT GREEN (-1015 4005);
FORCEPROP 1 LAST PATH I66
R 3
J 2
(-1000 4000);
DISPLAY 1.212766 (-1000 4000);
PAINT GREEN (-1000 4000);
DISPLAY INVISIBLE (-1000 4000);
FORCEPROP 1 LAST CDS_LMAN_SYM_OUTLINE 0,0,400,-700
R 3
J 0
(-1050 3950);
DISPLAY 0.468085 (-1050 3950);
PAINT GREEN (-1050 3950);
DISPLAY INVISIBLE (-1050 3950);
FORCEPROP 2 LAST CDS_LIB interface
J 0
(-1050 3950);
DISPLAY INVISIBLE (-1050 3950);
FORCEADD CAPACITOR..1
(-1450 3250);
FORCEPROP 1 LAST $LOCATION C305
J 2
(-1588 3300);
DISPLAY 1.212766 (-1588 3300);
PAINT GREEN (-1588 3300);
FORCEPROP 0 LAST CDS_LOCATION C305
J 0
(-1500 3400);
DISPLAY 1.021277 (-1500 3400);
DISPLAY INVISIBLE (-1500 3400);
FORCEPROP 0 LAST $SEC 1
J 0
(-1500 3400);
DISPLAY 0.680851 (-1500 3400);
PAINT MONO (-1500 3400);
DISPLAY INVISIBLE (-1500 3400);
FORCEPROP 0 LAST CDS_SEC 1
J 0
(-1500 3400);
DISPLAY 1.021277 (-1500 3400);
DISPLAY INVISIBLE (-1500 3400);
FORCEPROP 0 LASTPIN (-1550 3250) $PN 1
J 2
(-1560 3260);
DISPLAY 0.680851 (-1560 3260);
PAINT MONO (-1560 3260);
FORCEPROP 0 LASTPIN (-1300 3250) $PN 2
J 0
(-1290 3260);
DISPLAY 0.680851 (-1290 3260);
PAINT MONO (-1290 3260);
FORCEPROP 0 LAST VOLTAGE 25V
J 0
(-1500 3450);
DISPLAY 1.021277 (-1500 3450);
FORCEPROP 0 LAST PACKAGE 0402
J 0
(-1500 3350);
DISPLAY 1.021277 (-1500 3350);
FORCEPROP 1 LAST VALUE 0.1UF
J 0
(-1200 3250);
DISPLAY 1.212766 (-1200 3250);
PAINT GREEN (-1200 3250);
FORCEPROP 1 LAST PATH I67
J 2
(-1500 3350);
DISPLAY 1.212766 (-1500 3350);
PAINT GREEN (-1500 3350);
DISPLAY INVISIBLE (-1500 3350);
FORCEPROP 2 LAST CDS_LIB passive
J 0
(-1450 3250);
DISPLAY INVISIBLE (-1450 3250);
FORCEPROP 1 LAST CDS_LMAN_SYM_OUTLINE 0,50,50,-50
J 0
(-1450 3250);
DISPLAY 0.468085 (-1450 3250);
PAINT GREEN (-1450 3250);
DISPLAY INVISIBLE (-1450 3250);
FORCEPROP 1 LAST CLS_PN G105-0B104-EK
J 2
(-1500 3350);
DISPLAY 1.212766 (-1500 3350);
PAINT GREEN (-1500 3350);
DISPLAY INVISIBLE (-1500 3350);
FORCEPROP 1 LAST TOLERANCE 10%
J 2
(-1550 3350);
DISPLAY 1.212766 (-1550 3350);
PAINT GREEN (-1550 3350);
DISPLAY INVISIBLE (-1550 3350);
FORCEADD GND_SG..1
(-2100 3000);
FORCEPROP 3 LASTPIN (-2050 3050) SIG_NAME SG\g
J 0
(-2040 3060);
DISPLAY 0.659574 (-2040 3060);
PAINT MONO (-2040 3060);
DISPLAY INVISIBLE (-2040 3060);
FORCEPROP 1 LAST HDL_POWER SG
J 1
(-2045 2905);
DISPLAY 0.808511 (-2045 2905);
PAINT GREEN (-2045 2905);
FORCEPROP 1 LAST PATH I68
J 0
(-2065 3000);
DISPLAY 0.808511 (-2065 3000);
PAINT GREEN (-2065 3000);
DISPLAY INVISIBLE (-2065 3000);
FORCEPROP 1 LAST BODY_TYPE PLUMBING
J 0
(-2085 2985);
DISPLAY 0.808511 (-2085 2985);
PAINT GREEN (-2085 2985);
DISPLAY INVISIBLE (-2085 2985);
FORCEPROP 1 LAST CDS_LMAN_SYM_OUTLINE 0,0,100,-50
J 0
(-2100 3000);
DISPLAY 0.468085 (-2100 3000);
PAINT GREEN (-2100 3000);
DISPLAY INVISIBLE (-2100 3000);
FORCEPROP 2 LAST CDS_LIB cls
J 0
(-2100 3000);
DISPLAY INVISIBLE (-2100 3000);
FORCEADD RESISTOR..2
(-3000 5000);
FORCEPROP 1 LAST $LOCATION R418
J 0
(-2950 4850);
DISPLAY 1.212766 (-2950 4850);
PAINT GREEN (-2950 4850);
FORCEPROP 0 LAST CDS_LOCATION R418
J 0
(-2950 5200);
DISPLAY 1.021277 (-2950 5200);
DISPLAY INVISIBLE (-2950 5200);
FORCEPROP 0 LAST $SEC 1
J 0
(-2950 5200);
DISPLAY 0.680851 (-2950 5200);
PAINT MONO (-2950 5200);
DISPLAY INVISIBLE (-2950 5200);
FORCEPROP 0 LAST CDS_SEC 1
J 0
(-2950 5200);
DISPLAY 1.021277 (-2950 5200);
DISPLAY INVISIBLE (-2950 5200);
FORCEPROP 0 LASTPIN (-3000 5100) $PN 1
R 1
J 0
(-3010 5110);
DISPLAY 0.680851 (-3010 5110);
PAINT MONO (-3010 5110);
FORCEPROP 0 LASTPIN (-3000 4850) $PN 2
R 1
J 2
(-3010 4840);
DISPLAY 0.680851 (-3010 4840);
PAINT MONO (-3010 4840);
FORCEPROP 1 LAST VALUE 4.7KOHM
J 0
(-2950 5050);
DISPLAY 0.978723 (-2950 5050);
PAINT GREEN (-2950 5050);
FORCEPROP 0 LAST PACKAGE 0402
J 0
(-2950 5150);
DISPLAY 1.021277 (-2950 5150);
FORCEPROP 1 LAST PATH I69
J 0
(-3197 5105);
DISPLAY 1.212766 (-3197 5105);
PAINT GREEN (-3197 5105);
DISPLAY INVISIBLE (-3197 5105);
FORCEPROP 1 LAST TOLERANCE 1%
J 0
(-3197 5255);
DISPLAY 1.212766 (-3197 5255);
PAINT GREEN (-3197 5255);
DISPLAY INVISIBLE (-3197 5255);
FORCEPROP 1 LAST CLS_PN G155-14701-01
J 0
(-3136 5200);
DISPLAY 1.212766 (-3136 5200);
PAINT GREEN (-3136 5200);
DISPLAY INVISIBLE (-3136 5200);
FORCEPROP 1 LAST CDS_LMAN_SYM_OUTLINE -50,50,50,-100
J 0
(-3000 5000);
DISPLAY 0.468085 (-3000 5000);
PAINT GREEN (-3000 5000);
DISPLAY INVISIBLE (-3000 5000);
FORCEPROP 2 LAST CDS_LIB passive
J 0
(-3000 5000);
DISPLAY INVISIBLE (-3000 5000);
FORCEADD RESISTOR..2
(-3400 5000);
FORCEPROP 1 LAST $LOCATION R412
J 0
(-3350 4850);
DISPLAY 1.212766 (-3350 4850);
PAINT GREEN (-3350 4850);
FORCEPROP 0 LAST CDS_LOCATION R412
J 0
(-3350 5200);
DISPLAY 1.021277 (-3350 5200);
DISPLAY INVISIBLE (-3350 5200);
FORCEPROP 0 LAST $SEC 1
J 0
(-3350 5200);
DISPLAY 0.680851 (-3350 5200);
PAINT MONO (-3350 5200);
DISPLAY INVISIBLE (-3350 5200);
FORCEPROP 0 LAST CDS_SEC 1
J 0
(-3350 5200);
DISPLAY 1.021277 (-3350 5200);
DISPLAY INVISIBLE (-3350 5200);
FORCEPROP 0 LASTPIN (-3400 5100) $PN 1
R 1
J 0
(-3410 5110);
DISPLAY 0.680851 (-3410 5110);
PAINT MONO (-3410 5110);
FORCEPROP 0 LASTPIN (-3400 4850) $PN 2
R 1
J 2
(-3410 4840);
DISPLAY 0.680851 (-3410 4840);
PAINT MONO (-3410 4840);
FORCEPROP 0 LAST NO_ASSY TRUE
J 0
(-3500 4950);
DISPLAY 0.808511 (-3500 4950);
DISPLAY BOTH (-3500 4950);
FORCEPROP 1 LAST VALUE 4.7KOHM
J 0
(-3350 5050);
DISPLAY 0.978723 (-3350 5050);
PAINT GREEN (-3350 5050);
FORCEPROP 0 LAST PACKAGE 0402
J 0
(-3350 5150);
DISPLAY 1.021277 (-3350 5150);
FORCEPROP 1 LAST PATH I70
J 0
(-3597 5105);
DISPLAY 1.212766 (-3597 5105);
PAINT GREEN (-3597 5105);
DISPLAY INVISIBLE (-3597 5105);
FORCEPROP 1 LAST TOLERANCE 1%
J 0
(-3597 5255);
DISPLAY 1.212766 (-3597 5255);
PAINT GREEN (-3597 5255);
DISPLAY INVISIBLE (-3597 5255);
FORCEPROP 1 LAST CLS_PN G155-14701-01
J 0
(-3536 5200);
DISPLAY 1.212766 (-3536 5200);
PAINT GREEN (-3536 5200);
DISPLAY INVISIBLE (-3536 5200);
FORCEPROP 1 LAST CDS_LMAN_SYM_OUTLINE -50,50,50,-100
J 0
(-3400 5000);
DISPLAY 0.468085 (-3400 5000);
PAINT GREEN (-3400 5000);
DISPLAY INVISIBLE (-3400 5000);
FORCEPROP 2 LAST CDS_LIB passive
J 0
(-3400 5000);
DISPLAY INVISIBLE (-3400 5000);
FORCEADD RESISTOR..2
(-3850 5000);
FORCEPROP 1 LAST $LOCATION R408
J 0
(-3800 4850);
DISPLAY 1.212766 (-3800 4850);
PAINT GREEN (-3800 4850);
FORCEPROP 0 LAST CDS_LOCATION R408
J 0
(-3800 5200);
DISPLAY 1.021277 (-3800 5200);
DISPLAY INVISIBLE (-3800 5200);
FORCEPROP 0 LAST $SEC 1
J 0
(-3800 5200);
DISPLAY 0.680851 (-3800 5200);
PAINT MONO (-3800 5200);
DISPLAY INVISIBLE (-3800 5200);
FORCEPROP 0 LAST CDS_SEC 1
J 0
(-3800 5200);
DISPLAY 1.021277 (-3800 5200);
DISPLAY INVISIBLE (-3800 5200);
FORCEPROP 0 LASTPIN (-3850 5100) $PN 1
R 1
J 0
(-3860 5110);
DISPLAY 0.680851 (-3860 5110);
PAINT MONO (-3860 5110);
FORCEPROP 0 LASTPIN (-3850 4850) $PN 2
R 1
J 2
(-3860 4840);
DISPLAY 0.680851 (-3860 4840);
PAINT MONO (-3860 4840);
FORCEPROP 1 LAST VALUE 4.7KOHM
J 0
(-3800 5050);
DISPLAY 0.978723 (-3800 5050);
PAINT GREEN (-3800 5050);
FORCEPROP 0 LAST PACKAGE 0402
J 0
(-3800 5150);
DISPLAY 1.021277 (-3800 5150);
FORCEPROP 0 LAST NO_ASSY TRUE
J 0
(-4000 4950);
DISPLAY 0.808511 (-4000 4950);
DISPLAY BOTH (-4000 4950);
FORCEPROP 1 LAST PATH I71
J 0
(-4047 5105);
DISPLAY 1.212766 (-4047 5105);
PAINT GREEN (-4047 5105);
DISPLAY INVISIBLE (-4047 5105);
FORCEPROP 1 LAST TOLERANCE 1%
J 0
(-4047 5255);
DISPLAY 1.212766 (-4047 5255);
PAINT GREEN (-4047 5255);
DISPLAY INVISIBLE (-4047 5255);
FORCEPROP 1 LAST CLS_PN G155-14701-01
J 0
(-3986 5200);
DISPLAY 1.212766 (-3986 5200);
PAINT GREEN (-3986 5200);
DISPLAY INVISIBLE (-3986 5200);
FORCEPROP 1 LAST CDS_LMAN_SYM_OUTLINE -50,50,50,-100
J 0
(-3850 5000);
DISPLAY 0.468085 (-3850 5000);
PAINT GREEN (-3850 5000);
DISPLAY INVISIBLE (-3850 5000);
FORCEPROP 2 LAST CDS_LIB passive
J 0
(-3850 5000);
DISPLAY INVISIBLE (-3850 5000);
FORCEADD RESISTOR..2
(-3020 3740);
FORCEPROP 1 LAST $LOCATION R416
J 0
(-2970 3590);
DISPLAY 1.212766 (-2970 3590);
PAINT GREEN (-2970 3590);
FORCEPROP 0 LAST CDS_LOCATION R416
J 0
(-2950 3950);
DISPLAY 1.021277 (-2950 3950);
DISPLAY INVISIBLE (-2950 3950);
FORCEPROP 0 LAST $SEC 1
J 0
(-2950 3950);
DISPLAY 0.680851 (-2950 3950);
PAINT MONO (-2950 3950);
DISPLAY INVISIBLE (-2950 3950);
FORCEPROP 0 LAST CDS_SEC 1
J 0
(-2950 3950);
DISPLAY 1.021277 (-2950 3950);
DISPLAY INVISIBLE (-2950 3950);
FORCEPROP 0 LASTPIN (-3020 3840) $PN 1
R 1
J 0
(-3030 3850);
DISPLAY 0.680851 (-3030 3850);
PAINT MONO (-3030 3850);
FORCEPROP 0 LASTPIN (-3020 3590) $PN 2
R 1
J 2
(-3030 3580);
DISPLAY 0.680851 (-3030 3580);
PAINT MONO (-3030 3580);
FORCEPROP 0 LAST PACKAGE 0402
J 0
(-2950 3900);
DISPLAY 1.021277 (-2950 3900);
FORCEPROP 1 LAST VALUE 1KOHM
J 0
(-2950 3750);
DISPLAY 1.212766 (-2950 3750);
PAINT GREEN (-2950 3750);
FORCEPROP 0 LAST NO_ASSY TRUE
J 0
(-2950 3700);
DISPLAY 0.808511 (-2950 3700);
DISPLAY BOTH (-2950 3700);
FORCEPROP 1 LAST PATH I72
J 0
(-3217 3845);
DISPLAY 1.212766 (-3217 3845);
PAINT GREEN (-3217 3845);
DISPLAY INVISIBLE (-3217 3845);
FORCEPROP 1 LAST TOLERANCE 1%
J 0
(-3217 3995);
DISPLAY 1.212766 (-3217 3995);
PAINT GREEN (-3217 3995);
DISPLAY INVISIBLE (-3217 3995);
FORCEPROP 1 LAST CLS_PN G155-11001-01
J 0
(-3156 3940);
DISPLAY 1.212766 (-3156 3940);
PAINT GREEN (-3156 3940);
DISPLAY INVISIBLE (-3156 3940);
FORCEPROP 1 LAST CDS_LMAN_SYM_OUTLINE -50,50,50,-100
J 0
(-3020 3740);
DISPLAY 0.468085 (-3020 3740);
PAINT GREEN (-3020 3740);
DISPLAY INVISIBLE (-3020 3740);
FORCEPROP 2 LAST CDS_LIB passive
J 0
(-3020 3740);
DISPLAY INVISIBLE (-3020 3740);
FORCEADD RESISTOR..2
(-3850 3750);
FORCEPROP 1 LAST $LOCATION R409
J 0
(-3800 3600);
DISPLAY 1.212766 (-3800 3600);
PAINT GREEN (-3800 3600);
FORCEPROP 0 LAST CDS_LOCATION R409
J 0
(-3800 4000);
DISPLAY 1.021277 (-3800 4000);
DISPLAY INVISIBLE (-3800 4000);
FORCEPROP 0 LAST $SEC 1
J 0
(-3800 4000);
DISPLAY 0.680851 (-3800 4000);
PAINT MONO (-3800 4000);
DISPLAY INVISIBLE (-3800 4000);
FORCEPROP 0 LAST CDS_SEC 1
J 0
(-3800 4000);
DISPLAY 1.021277 (-3800 4000);
DISPLAY INVISIBLE (-3800 4000);
FORCEPROP 0 LASTPIN (-3850 3850) $PN 1
R 1
J 0
(-3860 3860);
DISPLAY 0.680851 (-3860 3860);
PAINT MONO (-3860 3860);
FORCEPROP 0 LASTPIN (-3850 3600) $PN 2
R 1
J 2
(-3860 3590);
DISPLAY 0.680851 (-3860 3590);
PAINT MONO (-3860 3590);
FORCEPROP 0 LAST PACKAGE 0402
J 0
(-3800 3950);
DISPLAY 1.021277 (-3800 3950);
FORCEPROP 1 LAST VALUE 1KOHM
J 0
(-3800 3800);
DISPLAY 1.212766 (-3800 3800);
PAINT GREEN (-3800 3800);
FORCEPROP 1 LAST PATH I73
J 0
(-4047 3855);
DISPLAY 1.212766 (-4047 3855);
PAINT GREEN (-4047 3855);
DISPLAY INVISIBLE (-4047 3855);
FORCEPROP 1 LAST TOLERANCE 1%
J 0
(-4047 4005);
DISPLAY 1.212766 (-4047 4005);
PAINT GREEN (-4047 4005);
DISPLAY INVISIBLE (-4047 4005);
FORCEPROP 1 LAST CLS_PN G155-11001-01
J 0
(-3986 3950);
DISPLAY 1.212766 (-3986 3950);
PAINT GREEN (-3986 3950);
DISPLAY INVISIBLE (-3986 3950);
FORCEPROP 1 LAST CDS_LMAN_SYM_OUTLINE -50,50,50,-100
J 0
(-3850 3750);
DISPLAY 0.468085 (-3850 3750);
PAINT GREEN (-3850 3750);
DISPLAY INVISIBLE (-3850 3750);
FORCEPROP 2 LAST CDS_LIB passive
J 0
(-3850 3750);
DISPLAY INVISIBLE (-3850 3750);
FORCEADD GND_SG..1
(-3900 3300);
FORCEPROP 3 LASTPIN (-3850 3350) SIG_NAME SG\g
J 0
(-3840 3360);
DISPLAY 0.659574 (-3840 3360);
PAINT MONO (-3840 3360);
DISPLAY INVISIBLE (-3840 3360);
FORCEPROP 1 LAST HDL_POWER SG
J 1
(-3845 3205);
DISPLAY 0.808511 (-3845 3205);
PAINT GREEN (-3845 3205);
FORCEPROP 1 LAST PATH I74
J 0
(-3865 3300);
DISPLAY 0.808511 (-3865 3300);
PAINT GREEN (-3865 3300);
DISPLAY INVISIBLE (-3865 3300);
FORCEPROP 1 LAST BODY_TYPE PLUMBING
J 0
(-3885 3285);
DISPLAY 0.808511 (-3885 3285);
PAINT GREEN (-3885 3285);
DISPLAY INVISIBLE (-3885 3285);
FORCEPROP 1 LAST CDS_LMAN_SYM_OUTLINE 0,0,100,-50
J 0
(-3900 3300);
DISPLAY 0.468085 (-3900 3300);
PAINT GREEN (-3900 3300);
DISPLAY INVISIBLE (-3900 3300);
FORCEPROP 2 LAST CDS_LIB cls
J 0
(-3900 3300);
DISPLAY INVISIBLE (-3900 3300);
FORCEADD RESISTOR..1
(-5600 4450);
FORCEPROP 1 LAST $LOCATION R406
J 2
(-5750 4450);
DISPLAY 1.212766 (-5750 4450);
PAINT GREEN (-5750 4450);
FORCEPROP 0 LAST CDS_LOCATION R406
J 0
(-5350 4550);
DISPLAY 1.021277 (-5350 4550);
DISPLAY INVISIBLE (-5350 4550);
FORCEPROP 0 LAST $SEC 1
J 0
(-5350 4550);
DISPLAY 0.680851 (-5350 4550);
PAINT MONO (-5350 4550);
DISPLAY INVISIBLE (-5350 4550);
FORCEPROP 0 LAST CDS_SEC 1
J 0
(-5350 4550);
DISPLAY 1.021277 (-5350 4550);
DISPLAY INVISIBLE (-5350 4550);
FORCEPROP 0 LASTPIN (-5700 4450) $PN 1
J 2
(-5710 4460);
DISPLAY 0.680851 (-5710 4460);
PAINT MONO (-5710 4460);
FORCEPROP 0 LASTPIN (-5450 4450) $PN 2
J 0
(-5440 4460);
DISPLAY 0.680851 (-5440 4460);
PAINT MONO (-5440 4460);
FORCEPROP 1 LAST VALUE 33OHM
J 0
(-5361 4455);
DISPLAY 1.212766 (-5361 4455);
PAINT GREEN (-5361 4455);
FORCEPROP 0 LAST PACKAGE 0402
J 0
(-5650 4350);
DISPLAY 1.021277 (-5650 4350);
FORCEPROP 1 LAST PATH I76
J 0
(-5797 4555);
DISPLAY 1.212766 (-5797 4555);
PAINT GREEN (-5797 4555);
DISPLAY INVISIBLE (-5797 4555);
FORCEPROP 1 LAST TOLERANCE 1%
J 0
(-5797 4705);
DISPLAY 1.212766 (-5797 4705);
PAINT GREEN (-5797 4705);
DISPLAY INVISIBLE (-5797 4705);
FORCEPROP 2 LAST CDS_LIB passive
J 0
(-5600 4450);
DISPLAY INVISIBLE (-5600 4450);
FORCEPROP 1 LAST CDS_LMAN_SYM_OUTLINE -50,50,100,-50
J 0
(-5600 4450);
DISPLAY 0.468085 (-5600 4450);
PAINT GREEN (-5600 4450);
DISPLAY INVISIBLE (-5600 4450);
FORCEPROP 1 LAST CLS_PN G155-133R0-01
J 0
(-5736 4650);
DISPLAY 1.212766 (-5736 4650);
PAINT GREEN (-5736 4650);
DISPLAY INVISIBLE (-5736 4650);
FORCEADD VCC..1
(-3900 5450);
FORCEPROP 3 LASTPIN (-3850 5400) SIG_NAME XP3R3V_FPGA\g
J 0
(-3840 5410);
DISPLAY 0.659574 (-3840 5410);
PAINT MONO (-3840 5410);
DISPLAY INVISIBLE (-3840 5410);
FORCEPROP 1 LAST HDL_POWER XP3R3V_FPGA
J 1
(-3845 5505);
DISPLAY 1.021277 (-3845 5505);
PAINT GREEN (-3845 5505);
FORCEPROP 0 LAST VOLTAGE 3.3V
J 0
(-4150 5600);
DISPLAY 1.021277 (-4150 5600);
DISPLAY BOTH (-4150 5600);
FORCEPROP 1 LAST PATH I77
J 0
(-3865 5540);
DISPLAY 0.808511 (-3865 5540);
PAINT GREEN (-3865 5540);
DISPLAY INVISIBLE (-3865 5540);
FORCEPROP 1 LAST BODY_TYPE PLUMBING
J 0
(-3945 5407);
DISPLAY 0.340426 (-3945 5407);
PAINT GREEN (-3945 5407);
DISPLAY INVISIBLE (-3945 5407);
FORCEPROP 2 LAST CDS_LIB cls
J 0
(-3900 5450);
DISPLAY INVISIBLE (-3900 5450);
FORCEPROP 1 LAST CDS_LMAN_SYM_OUTLINE -250,250,250,-250
J 0
(-3900 5450);
DISPLAY 0.468085 (-3900 5450);
PAINT GREEN (-3900 5450);
DISPLAY INVISIBLE (-3900 5450);
FORCEADD LM75BDP_TSSOP8..1
(-2700 1800);
FORCEPROP 1 LAST $LOCATION U36
J 0
(-2700 1950);
DISPLAY 1.212766 (-2700 1950);
PAINT GREEN (-2700 1950);
FORCEPROP 0 LAST CDS_LOCATION U36
J 0
(-2500 2050);
DISPLAY 1.021277 (-2500 2050);
DISPLAY INVISIBLE (-2500 2050);
FORCEPROP 0 LAST $SEC 1
J 0
(-2500 2050);
DISPLAY 0.680851 (-2500 2050);
PAINT MONO (-2500 2050);
DISPLAY INVISIBLE (-2500 2050);
FORCEPROP 0 LAST CDS_SEC 1
J 0
(-2500 2050);
DISPLAY 1.021277 (-2500 2050);
DISPLAY INVISIBLE (-2500 2050);
FORCEPROP 0 LASTPIN (-2800 1200) $PN 7
J 2
(-2810 1210);
DISPLAY 0.680851 (-2810 1210);
PAINT MONO (-2810 1210);
FORCEPROP 0 LASTPIN (-2800 1300) $PN 6
J 2
(-2810 1310);
DISPLAY 0.680851 (-2810 1310);
PAINT MONO (-2810 1310);
FORCEPROP 0 LASTPIN (-2800 1400) $PN 5
J 2
(-2810 1410);
DISPLAY 0.680851 (-2810 1410);
PAINT MONO (-2810 1410);
FORCEPROP 0 LASTPIN (-2100 1500) $PN 3
J 0
(-2090 1510);
DISPLAY 0.680851 (-2090 1510);
PAINT MONO (-2090 1510);
FORCEPROP 0 LASTPIN (-2800 1700) $PN 2
J 2
(-2810 1710);
DISPLAY 0.680851 (-2810 1710);
PAINT MONO (-2810 1710);
FORCEPROP 0 LASTPIN (-2800 1600) $PN 1
J 2
(-2810 1610);
DISPLAY 0.680851 (-2810 1610);
PAINT MONO (-2810 1610);
FORCEPROP 1 LAST CLS_PN G220-10215-01
J 0
(-2700 1850);
DISPLAY 1.212766 (-2700 1850);
PAINT GREEN (-2700 1850);
FORCEPROP 0 LAST PART_NUMBER LM75BDP,118
J 0
(-2500 2000);
DISPLAY 1.021277 (-2500 2000);
FORCEPROP 1 LAST PATH I81
J 0
(-2650 1850);
DISPLAY 1.212766 (-2650 1850);
PAINT GREEN (-2650 1850);
DISPLAY INVISIBLE (-2650 1850);
FORCEPROP 2 LASTPIN (-2800 1400) SIG_NAME UN$6$LM75BDPTSSOP8$I81$A2
J 0
(-2790 1410);
DISPLAY 0.659574 (-2790 1410);
PAINT MONO (-2790 1410);
DISPLAY INVISIBLE (-2790 1410);
FORCEPROP 2 LASTPIN (-2800 1300) SIG_NAME UN$6$LM75BDPTSSOP8$I81$A1
J 0
(-2790 1310);
DISPLAY 0.659574 (-2790 1310);
PAINT MONO (-2790 1310);
DISPLAY INVISIBLE (-2790 1310);
FORCEPROP 2 LASTPIN (-2800 1200) SIG_NAME UN$6$LM75BDPTSSOP8$I81$A0
J 0
(-2790 1210);
DISPLAY 0.659574 (-2790 1210);
PAINT MONO (-2790 1210);
DISPLAY INVISIBLE (-2790 1210);
FORCEPROP 1 LAST CDS_LMAN_SYM_OUTLINE 0,0,500,-800
J 0
(-2700 1800);
DISPLAY 0.468085 (-2700 1800);
PAINT GREEN (-2700 1800);
DISPLAY INVISIBLE (-2700 1800);
FORCEPROP 2 LAST CDS_LIB interface
J 0
(-2700 1800);
DISPLAY INVISIBLE (-2700 1800);
FORCEADD OFFPAGE_OUT..1
(300 1500);
FORCEPROP 2 LAST CDS_LIB cls
J 0
(300 1500);
DISPLAY INVISIBLE (300 1500);
FORCEPROP 1 LAST CDS_LMAN_SYM_OUTLINE -50,50,50,-50
J 0
(300 1500);
DISPLAY 0.468085 (300 1500);
PAINT GREEN (300 1500);
DISPLAY INVISIBLE (300 1500);
FORCEPROP 2 LAST PATH I82
J 0
(350 1600);
DISPLAY 1.021277 (350 1600);
DISPLAY INVISIBLE (350 1600);
FORCEPROP 1 LAST OFFPAGE TRUE
J 0
(310 1555);
DISPLAY 0.808511 (310 1555);
PAINT GREEN (310 1555);
DISPLAY INVISIBLE (310 1555);
FORCEPROP 1 LAST BODY_TYPE COMMENT
J 0
(310 1635);
DISPLAY 0.808511 (310 1635);
PAINT GREEN (310 1635);
DISPLAY INVISIBLE (310 1635);
FORCEPROP 2 LAST $XR1 12G5< 
J 0
(565 1500);
DISPLAY 0.638298 (565 1500);
PAINT MONO (565 1500);
FORCEPROP 2 LAST $XR0 25D6<> 
J 0
(355 1500);
DISPLAY 0.638298 (355 1500);
PAINT MONO (355 1500);
FORCEADD VCC..1
(-1250 2150);
FORCEPROP 3 LASTPIN (-1200 2100) SIG_NAME XP3R3V_FPGA\g
J 0
(-1190 2110);
DISPLAY 0.659574 (-1190 2110);
PAINT MONO (-1190 2110);
DISPLAY INVISIBLE (-1190 2110);
FORCEPROP 1 LAST HDL_POWER XP3R3V_FPGA
J 1
(-1195 2205);
DISPLAY 1.021277 (-1195 2205);
PAINT GREEN (-1195 2205);
FORCEPROP 0 LAST VOLTAGE 3.3V
J 0
(-1500 2300);
DISPLAY 1.021277 (-1500 2300);
DISPLAY BOTH (-1500 2300);
FORCEPROP 2 LAST CDS_LIB cls
J 0
(-1250 2150);
DISPLAY INVISIBLE (-1250 2150);
FORCEPROP 1 LAST CDS_LMAN_SYM_OUTLINE -250,250,250,-250
J 0
(-1250 2150);
DISPLAY 0.468085 (-1250 2150);
PAINT GREEN (-1250 2150);
DISPLAY INVISIBLE (-1250 2150);
FORCEPROP 1 LAST BODY_TYPE PLUMBING
J 0
(-1295 2107);
DISPLAY 0.340426 (-1295 2107);
PAINT GREEN (-1295 2107);
DISPLAY INVISIBLE (-1295 2107);
FORCEPROP 1 LAST PATH I83
J 0
(-1215 2240);
DISPLAY 0.808511 (-1215 2240);
PAINT GREEN (-1215 2240);
DISPLAY INVISIBLE (-1215 2240);
FORCEADD RESISTOR..2
(-3000 2150);
FORCEPROP 1 LAST $LOCATION R419
J 0
(-2950 2000);
DISPLAY 1.212766 (-2950 2000);
PAINT GREEN (-2950 2000);
FORCEPROP 0 LAST CDS_LOCATION R419
J 0
(-2950 2350);
DISPLAY 1.021277 (-2950 2350);
DISPLAY INVISIBLE (-2950 2350);
FORCEPROP 0 LAST $SEC 1
J 0
(-2950 2350);
DISPLAY 0.680851 (-2950 2350);
PAINT MONO (-2950 2350);
DISPLAY INVISIBLE (-2950 2350);
FORCEPROP 0 LAST CDS_SEC 1
J 0
(-2950 2350);
DISPLAY 1.021277 (-2950 2350);
DISPLAY INVISIBLE (-2950 2350);
FORCEPROP 0 LASTPIN (-3000 2250) $PN 1
R 1
J 0
(-3010 2260);
DISPLAY 0.680851 (-3010 2260);
PAINT MONO (-3010 2260);
FORCEPROP 0 LASTPIN (-3000 2000) $PN 2
R 1
J 2
(-3010 1990);
DISPLAY 0.680851 (-3010 1990);
PAINT MONO (-3010 1990);
FORCEPROP 1 LAST VALUE 4.7KOHM
J 0
(-2950 2200);
DISPLAY 0.978723 (-2950 2200);
PAINT GREEN (-2950 2200);
FORCEPROP 0 LAST PACKAGE 0402
J 0
(-2950 2300);
DISPLAY 1.021277 (-2950 2300);
FORCEPROP 0 LAST NO_ASSY TRUE
J 0
(-2950 2100);
DISPLAY 0.808511 (-2950 2100);
DISPLAY BOTH (-2950 2100);
FORCEPROP 1 LAST PATH I84
J 0
(-3197 2255);
DISPLAY 1.212766 (-3197 2255);
PAINT GREEN (-3197 2255);
DISPLAY INVISIBLE (-3197 2255);
FORCEPROP 1 LAST TOLERANCE 1%
J 0
(-3197 2405);
DISPLAY 1.212766 (-3197 2405);
PAINT GREEN (-3197 2405);
DISPLAY INVISIBLE (-3197 2405);
FORCEPROP 1 LAST CLS_PN G155-14701-01
J 0
(-3136 2350);
DISPLAY 1.212766 (-3136 2350);
PAINT GREEN (-3136 2350);
DISPLAY INVISIBLE (-3136 2350);
FORCEPROP 1 LAST CDS_LMAN_SYM_OUTLINE -50,50,50,-100
J 0
(-3000 2150);
DISPLAY 0.468085 (-3000 2150);
PAINT GREEN (-3000 2150);
DISPLAY INVISIBLE (-3000 2150);
FORCEPROP 2 LAST CDS_LIB passive
J 0
(-3000 2150);
DISPLAY INVISIBLE (-3000 2150);
FORCEADD RESISTOR..2
(-3400 2150);
FORCEPROP 1 LAST $LOCATION R414
J 0
(-3350 2000);
DISPLAY 1.212766 (-3350 2000);
PAINT GREEN (-3350 2000);
FORCEPROP 0 LAST CDS_LOCATION R414
J 0
(-3350 2350);
DISPLAY 1.021277 (-3350 2350);
DISPLAY INVISIBLE (-3350 2350);
FORCEPROP 0 LAST $SEC 1
J 0
(-3350 2350);
DISPLAY 0.680851 (-3350 2350);
PAINT MONO (-3350 2350);
DISPLAY INVISIBLE (-3350 2350);
FORCEPROP 0 LAST CDS_SEC 1
J 0
(-3350 2350);
DISPLAY 1.021277 (-3350 2350);
DISPLAY INVISIBLE (-3350 2350);
FORCEPROP 0 LASTPIN (-3400 2250) $PN 1
R 1
J 0
(-3410 2260);
DISPLAY 0.680851 (-3410 2260);
PAINT MONO (-3410 2260);
FORCEPROP 0 LASTPIN (-3400 2000) $PN 2
R 1
J 2
(-3410 1990);
DISPLAY 0.680851 (-3410 1990);
PAINT MONO (-3410 1990);
FORCEPROP 1 LAST VALUE 4.7KOHM
J 0
(-3350 2200);
DISPLAY 0.978723 (-3350 2200);
PAINT GREEN (-3350 2200);
FORCEPROP 0 LAST PACKAGE 0402
J 0
(-3350 2300);
DISPLAY 1.021277 (-3350 2300);
FORCEPROP 1 LAST PATH I85
J 0
(-3597 2255);
DISPLAY 1.212766 (-3597 2255);
PAINT GREEN (-3597 2255);
DISPLAY INVISIBLE (-3597 2255);
FORCEPROP 1 LAST TOLERANCE 1%
J 0
(-3597 2405);
DISPLAY 1.212766 (-3597 2405);
PAINT GREEN (-3597 2405);
DISPLAY INVISIBLE (-3597 2405);
FORCEPROP 1 LAST CLS_PN G155-14701-01
J 0
(-3536 2350);
DISPLAY 1.212766 (-3536 2350);
PAINT GREEN (-3536 2350);
DISPLAY INVISIBLE (-3536 2350);
FORCEPROP 1 LAST CDS_LMAN_SYM_OUTLINE -50,50,50,-100
J 0
(-3400 2150);
DISPLAY 0.468085 (-3400 2150);
PAINT GREEN (-3400 2150);
DISPLAY INVISIBLE (-3400 2150);
FORCEPROP 2 LAST CDS_LIB passive
J 0
(-3400 2150);
DISPLAY INVISIBLE (-3400 2150);
FORCEADD RESISTOR..2
(-3850 2150);
FORCEPROP 1 LAST $LOCATION R410
J 0
(-3800 2000);
DISPLAY 1.212766 (-3800 2000);
PAINT GREEN (-3800 2000);
FORCEPROP 0 LAST CDS_LOCATION R410
J 0
(-3800 2350);
DISPLAY 1.021277 (-3800 2350);
DISPLAY INVISIBLE (-3800 2350);
FORCEPROP 0 LAST $SEC 1
J 0
(-3800 2350);
DISPLAY 0.680851 (-3800 2350);
PAINT MONO (-3800 2350);
DISPLAY INVISIBLE (-3800 2350);
FORCEPROP 0 LAST CDS_SEC 1
J 0
(-3800 2350);
DISPLAY 1.021277 (-3800 2350);
DISPLAY INVISIBLE (-3800 2350);
FORCEPROP 0 LASTPIN (-3850 2250) $PN 1
R 1
J 0
(-3860 2260);
DISPLAY 0.680851 (-3860 2260);
PAINT MONO (-3860 2260);
FORCEPROP 0 LASTPIN (-3850 2000) $PN 2
R 1
J 2
(-3860 1990);
DISPLAY 0.680851 (-3860 1990);
PAINT MONO (-3860 1990);
FORCEPROP 1 LAST VALUE 4.7KOHM
J 0
(-3800 2200);
DISPLAY 0.978723 (-3800 2200);
PAINT GREEN (-3800 2200);
FORCEPROP 0 LAST PACKAGE 0402
J 0
(-3800 2300);
DISPLAY 1.021277 (-3800 2300);
FORCEPROP 0 LAST NO_ASSY TRUE
J 0
(-4000 2100);
DISPLAY 0.808511 (-4000 2100);
DISPLAY BOTH (-4000 2100);
FORCEPROP 1 LAST PATH I86
J 0
(-4047 2255);
DISPLAY 1.212766 (-4047 2255);
PAINT GREEN (-4047 2255);
DISPLAY INVISIBLE (-4047 2255);
FORCEPROP 1 LAST TOLERANCE 1%
J 0
(-4047 2405);
DISPLAY 1.212766 (-4047 2405);
PAINT GREEN (-4047 2405);
DISPLAY INVISIBLE (-4047 2405);
FORCEPROP 1 LAST CLS_PN G155-14701-01
J 0
(-3986 2350);
DISPLAY 1.212766 (-3986 2350);
PAINT GREEN (-3986 2350);
DISPLAY INVISIBLE (-3986 2350);
FORCEPROP 1 LAST CDS_LMAN_SYM_OUTLINE -50,50,50,-100
J 0
(-3850 2150);
DISPLAY 0.468085 (-3850 2150);
PAINT GREEN (-3850 2150);
DISPLAY INVISIBLE (-3850 2150);
FORCEPROP 2 LAST CDS_LIB passive
J 0
(-3850 2150);
DISPLAY INVISIBLE (-3850 2150);
FORCEADD VCC..1
(-600 1050);
FORCEPROP 3 LASTPIN (-550 1000) SIG_NAME XP3R3V_FPGA\g
J 0
(-540 1010);
DISPLAY 0.659574 (-540 1010);
PAINT MONO (-540 1010);
DISPLAY INVISIBLE (-540 1010);
FORCEPROP 0 LAST VOLTAGE 3.3V
J 0
(-850 1200);
DISPLAY 1.021277 (-850 1200);
DISPLAY BOTH (-850 1200);
FORCEPROP 1 LAST HDL_POWER XP3R3V_FPGA
J 1
(-545 1105);
DISPLAY 1.021277 (-545 1105);
PAINT GREEN (-545 1105);
FORCEPROP 1 LAST PATH I87
J 0
(-565 1140);
DISPLAY 0.808511 (-565 1140);
PAINT GREEN (-565 1140);
DISPLAY INVISIBLE (-565 1140);
FORCEPROP 1 LAST BODY_TYPE PLUMBING
J 0
(-645 1007);
DISPLAY 0.340426 (-645 1007);
PAINT GREEN (-645 1007);
DISPLAY INVISIBLE (-645 1007);
FORCEPROP 1 LAST CDS_LMAN_SYM_OUTLINE -250,250,250,-250
J 0
(-600 1050);
DISPLAY 0.468085 (-600 1050);
PAINT GREEN (-600 1050);
DISPLAY INVISIBLE (-600 1050);
FORCEPROP 2 LAST CDS_LIB cls
J 0
(-600 1050);
DISPLAY INVISIBLE (-600 1050);
FORCEADD RESISTOR..2
(-1200 1900);
FORCEPROP 1 LAST $LOCATION R423
J 0
(-1150 1750);
DISPLAY 1.212766 (-1150 1750);
PAINT GREEN (-1150 1750);
FORCEPROP 0 LAST CDS_LOCATION R423
J 0
(-1150 2050);
DISPLAY 1.021277 (-1150 2050);
DISPLAY INVISIBLE (-1150 2050);
FORCEPROP 0 LAST $SEC 1
J 0
(-1150 2050);
DISPLAY 0.680851 (-1150 2050);
PAINT MONO (-1150 2050);
DISPLAY INVISIBLE (-1150 2050);
FORCEPROP 0 LAST CDS_SEC 1
J 0
(-1150 2050);
DISPLAY 1.021277 (-1150 2050);
DISPLAY INVISIBLE (-1150 2050);
FORCEPROP 0 LASTPIN (-1200 2000) $PN 1
R 1
J 0
(-1210 2010);
DISPLAY 0.680851 (-1210 2010);
PAINT MONO (-1210 2010);
FORCEPROP 0 LASTPIN (-1200 1750) $PN 2
R 1
J 2
(-1210 1740);
DISPLAY 0.680851 (-1210 1740);
PAINT MONO (-1210 1740);
FORCEPROP 0 LAST PACKAGE 0402
J 0
(-1150 1850);
DISPLAY 1.021277 (-1150 1850);
FORCEPROP 1 LAST VALUE 4.7KOHM
J 0
(-1150 1950);
DISPLAY 1.212766 (-1150 1950);
PAINT GREEN (-1150 1950);
FORCEPROP 2 LAST CDS_LIB passive
J 0
(-1200 1900);
DISPLAY INVISIBLE (-1200 1900);
FORCEPROP 1 LAST CDS_LMAN_SYM_OUTLINE -50,50,50,-100
J 0
(-1200 1900);
DISPLAY 0.468085 (-1200 1900);
PAINT GREEN (-1200 1900);
DISPLAY INVISIBLE (-1200 1900);
FORCEPROP 1 LAST CLS_PN G155-14701-01
J 0
(-1336 2100);
DISPLAY 1.212766 (-1336 2100);
PAINT GREEN (-1336 2100);
DISPLAY INVISIBLE (-1336 2100);
FORCEPROP 1 LAST TOLERANCE 1%
J 0
(-1397 2155);
DISPLAY 1.212766 (-1397 2155);
PAINT GREEN (-1397 2155);
DISPLAY INVISIBLE (-1397 2155);
FORCEPROP 1 LAST PATH I88
J 0
(-1397 2005);
DISPLAY 1.212766 (-1397 2005);
PAINT GREEN (-1397 2005);
DISPLAY INVISIBLE (-1397 2005);
FORCEADD LM75BDP_TSSOP8..2
R 5
(-1050 1100);
FORCEPROP 1 LAST $LOCATION U35
J 2
(-1650 1250);
DISPLAY 1.212766 (-1650 1250);
PAINT GREEN (-1650 1250);
FORCEPROP 0 LAST CDS_LOCATION U35
J 0
(-1650 1350);
DISPLAY 1.021277 (-1650 1350);
DISPLAY INVISIBLE (-1650 1350);
FORCEPROP 0 LAST $SEC 2
J 0
(-1650 1350);
DISPLAY 0.680851 (-1650 1350);
PAINT MONO (-1650 1350);
DISPLAY INVISIBLE (-1650 1350);
FORCEPROP 0 LAST CDS_SEC 2
J 0
(-1650 1350);
DISPLAY 1.021277 (-1650 1350);
DISPLAY INVISIBLE (-1650 1350);
FORCEPROP 0 LASTPIN (-1850 900) $PN 4
J 2
(-1860 910);
DISPLAY 0.680851 (-1860 910);
PAINT MONO (-1860 910);
FORCEPROP 0 LASTPIN (-950 900) $PN 8
J 0
(-940 910);
DISPLAY 0.680851 (-940 910);
PAINT MONO (-940 910);
FORCEPROP 1 LAST CLS_PN G220-10215-01
J 2
(-1015 1155);
DISPLAY 1.212766 (-1015 1155);
PAINT GREEN (-1015 1155);
FORCEPROP 1 LAST PATH I90
R 3
J 2
(-1000 1150);
DISPLAY 1.212766 (-1000 1150);
PAINT GREEN (-1000 1150);
DISPLAY INVISIBLE (-1000 1150);
FORCEPROP 1 LAST CDS_LMAN_SYM_OUTLINE 0,0,400,-700
R 3
J 0
(-1050 1100);
DISPLAY 0.468085 (-1050 1100);
PAINT GREEN (-1050 1100);
DISPLAY INVISIBLE (-1050 1100);
FORCEPROP 2 LAST CDS_LIB interface
J 0
(-1050 1100);
DISPLAY INVISIBLE (-1050 1100);
FORCEADD CAPACITOR..1
(-1450 400);
FORCEPROP 1 LAST $LOCATION C306
J 2
(-1588 450);
DISPLAY 1.212766 (-1588 450);
PAINT GREEN (-1588 450);
FORCEPROP 0 LAST CDS_LOCATION C306
J 0
(-1500 550);
DISPLAY 1.021277 (-1500 550);
DISPLAY INVISIBLE (-1500 550);
FORCEPROP 0 LAST $SEC 1
J 0
(-1500 550);
DISPLAY 0.680851 (-1500 550);
PAINT MONO (-1500 550);
DISPLAY INVISIBLE (-1500 550);
FORCEPROP 0 LAST CDS_SEC 1
J 0
(-1500 550);
DISPLAY 1.021277 (-1500 550);
DISPLAY INVISIBLE (-1500 550);
FORCEPROP 0 LASTPIN (-1550 400) $PN 1
J 2
(-1560 410);
DISPLAY 0.680851 (-1560 410);
PAINT MONO (-1560 410);
FORCEPROP 0 LASTPIN (-1300 400) $PN 2
J 0
(-1290 410);
DISPLAY 0.680851 (-1290 410);
PAINT MONO (-1290 410);
FORCEPROP 0 LAST VOLTAGE 25V
J 0
(-1500 600);
DISPLAY 1.021277 (-1500 600);
FORCEPROP 0 LAST PACKAGE 0402
J 0
(-1500 500);
DISPLAY 1.021277 (-1500 500);
FORCEPROP 1 LAST VALUE 0.1UF
J 0
(-1200 400);
DISPLAY 1.212766 (-1200 400);
PAINT GREEN (-1200 400);
FORCEPROP 1 LAST PATH I91
J 2
(-1500 500);
DISPLAY 1.212766 (-1500 500);
PAINT GREEN (-1500 500);
DISPLAY INVISIBLE (-1500 500);
FORCEPROP 2 LAST CDS_LIB passive
J 0
(-1450 400);
DISPLAY INVISIBLE (-1450 400);
FORCEPROP 1 LAST CDS_LMAN_SYM_OUTLINE 0,50,50,-50
J 0
(-1450 400);
DISPLAY 0.468085 (-1450 400);
PAINT GREEN (-1450 400);
DISPLAY INVISIBLE (-1450 400);
FORCEPROP 1 LAST CLS_PN G105-0B104-EK
J 2
(-1500 500);
DISPLAY 1.212766 (-1500 500);
PAINT GREEN (-1500 500);
DISPLAY INVISIBLE (-1500 500);
FORCEPROP 1 LAST TOLERANCE 10%
J 2
(-1550 500);
DISPLAY 1.212766 (-1550 500);
PAINT GREEN (-1550 500);
DISPLAY INVISIBLE (-1550 500);
FORCEADD GND_SG..1
(-2100 150);
FORCEPROP 3 LASTPIN (-2050 200) SIG_NAME SG\g
J 0
(-2040 210);
DISPLAY 0.659574 (-2040 210);
PAINT MONO (-2040 210);
DISPLAY INVISIBLE (-2040 210);
FORCEPROP 1 LAST HDL_POWER SG
J 1
(-2045 55);
DISPLAY 0.808511 (-2045 55);
PAINT GREEN (-2045 55);
FORCEPROP 1 LAST PATH I92
J 0
(-2065 150);
DISPLAY 0.808511 (-2065 150);
PAINT GREEN (-2065 150);
DISPLAY INVISIBLE (-2065 150);
FORCEPROP 1 LAST BODY_TYPE PLUMBING
J 0
(-2085 135);
DISPLAY 0.808511 (-2085 135);
PAINT GREEN (-2085 135);
DISPLAY INVISIBLE (-2085 135);
FORCEPROP 1 LAST CDS_LMAN_SYM_OUTLINE 0,0,100,-50
J 0
(-2100 150);
DISPLAY 0.468085 (-2100 150);
PAINT GREEN (-2100 150);
DISPLAY INVISIBLE (-2100 150);
FORCEPROP 2 LAST CDS_LIB cls
J 0
(-2100 150);
DISPLAY INVISIBLE (-2100 150);
FORCEADD RESISTOR..2
(-3020 890);
FORCEPROP 1 LAST $LOCATION R417
J 0
(-2970 740);
DISPLAY 1.212766 (-2970 740);
PAINT GREEN (-2970 740);
FORCEPROP 0 LAST CDS_LOCATION R417
J 0
(-2950 1100);
DISPLAY 1.021277 (-2950 1100);
DISPLAY INVISIBLE (-2950 1100);
FORCEPROP 0 LAST $SEC 1
J 0
(-2950 1100);
DISPLAY 0.680851 (-2950 1100);
PAINT MONO (-2950 1100);
DISPLAY INVISIBLE (-2950 1100);
FORCEPROP 0 LAST CDS_SEC 1
J 0
(-2950 1100);
DISPLAY 1.021277 (-2950 1100);
DISPLAY INVISIBLE (-2950 1100);
FORCEPROP 0 LASTPIN (-3020 990) $PN 1
R 1
J 0
(-3030 1000);
DISPLAY 0.680851 (-3030 1000);
PAINT MONO (-3030 1000);
FORCEPROP 0 LASTPIN (-3020 740) $PN 2
R 1
J 2
(-3030 730);
DISPLAY 0.680851 (-3030 730);
PAINT MONO (-3030 730);
FORCEPROP 1 LAST VALUE 1KOHM
J 0
(-2950 900);
DISPLAY 1.212766 (-2950 900);
PAINT GREEN (-2950 900);
FORCEPROP 0 LAST PACKAGE 0402
J 0
(-2950 1050);
DISPLAY 1.021277 (-2950 1050);
FORCEPROP 1 LAST PATH I93
J 0
(-3217 995);
DISPLAY 1.212766 (-3217 995);
PAINT GREEN (-3217 995);
DISPLAY INVISIBLE (-3217 995);
FORCEPROP 1 LAST TOLERANCE 1%
J 0
(-3217 1145);
DISPLAY 1.212766 (-3217 1145);
PAINT GREEN (-3217 1145);
DISPLAY INVISIBLE (-3217 1145);
FORCEPROP 1 LAST CLS_PN G155-11001-01
J 0
(-3156 1090);
DISPLAY 1.212766 (-3156 1090);
PAINT GREEN (-3156 1090);
DISPLAY INVISIBLE (-3156 1090);
FORCEPROP 1 LAST CDS_LMAN_SYM_OUTLINE -50,50,50,-100
J 0
(-3020 890);
DISPLAY 0.468085 (-3020 890);
PAINT GREEN (-3020 890);
DISPLAY INVISIBLE (-3020 890);
FORCEPROP 2 LAST CDS_LIB passive
J 0
(-3020 890);
DISPLAY INVISIBLE (-3020 890);
FORCEADD RESISTOR..2
(-3400 900);
FORCEPROP 1 LAST $LOCATION R415
J 0
(-3350 750);
DISPLAY 1.212766 (-3350 750);
PAINT GREEN (-3350 750);
FORCEPROP 0 LAST CDS_LOCATION R415
J 0
(-3350 1150);
DISPLAY 1.021277 (-3350 1150);
DISPLAY INVISIBLE (-3350 1150);
FORCEPROP 0 LAST $SEC 1
J 0
(-3350 1150);
DISPLAY 0.680851 (-3350 1150);
PAINT MONO (-3350 1150);
DISPLAY INVISIBLE (-3350 1150);
FORCEPROP 0 LAST CDS_SEC 1
J 0
(-3350 1150);
DISPLAY 1.021277 (-3350 1150);
DISPLAY INVISIBLE (-3350 1150);
FORCEPROP 0 LASTPIN (-3400 1000) $PN 1
R 1
J 0
(-3410 1010);
DISPLAY 0.680851 (-3410 1010);
PAINT MONO (-3410 1010);
FORCEPROP 0 LASTPIN (-3400 750) $PN 2
R 1
J 2
(-3410 740);
DISPLAY 0.680851 (-3410 740);
PAINT MONO (-3410 740);
FORCEPROP 1 LAST VALUE 1KOHM
J 0
(-3350 950);
DISPLAY 1.212766 (-3350 950);
PAINT GREEN (-3350 950);
FORCEPROP 0 LAST PACKAGE 0402
J 0
(-3350 1100);
DISPLAY 1.021277 (-3350 1100);
FORCEPROP 0 LAST NO_ASSY TRUE
J 0
(-3550 850);
DISPLAY 0.808511 (-3550 850);
DISPLAY BOTH (-3550 850);
FORCEPROP 1 LAST PATH I94
J 0
(-3597 1005);
DISPLAY 1.212766 (-3597 1005);
PAINT GREEN (-3597 1005);
DISPLAY INVISIBLE (-3597 1005);
FORCEPROP 1 LAST TOLERANCE 1%
J 0
(-3597 1155);
DISPLAY 1.212766 (-3597 1155);
PAINT GREEN (-3597 1155);
DISPLAY INVISIBLE (-3597 1155);
FORCEPROP 1 LAST CLS_PN G155-11001-01
J 0
(-3536 1100);
DISPLAY 1.212766 (-3536 1100);
PAINT GREEN (-3536 1100);
DISPLAY INVISIBLE (-3536 1100);
FORCEPROP 1 LAST CDS_LMAN_SYM_OUTLINE -50,50,50,-100
J 0
(-3400 900);
DISPLAY 0.468085 (-3400 900);
PAINT GREEN (-3400 900);
DISPLAY INVISIBLE (-3400 900);
FORCEPROP 2 LAST CDS_LIB passive
J 0
(-3400 900);
DISPLAY INVISIBLE (-3400 900);
FORCEADD RESISTOR..2
(-3850 900);
FORCEPROP 1 LAST $LOCATION R411
J 0
(-3800 750);
DISPLAY 1.212766 (-3800 750);
PAINT GREEN (-3800 750);
FORCEPROP 0 LAST CDS_LOCATION R411
J 0
(-3800 1150);
DISPLAY 1.021277 (-3800 1150);
DISPLAY INVISIBLE (-3800 1150);
FORCEPROP 0 LAST $SEC 1
J 0
(-3800 1150);
DISPLAY 0.680851 (-3800 1150);
PAINT MONO (-3800 1150);
DISPLAY INVISIBLE (-3800 1150);
FORCEPROP 0 LAST CDS_SEC 1
J 0
(-3800 1150);
DISPLAY 1.021277 (-3800 1150);
DISPLAY INVISIBLE (-3800 1150);
FORCEPROP 0 LASTPIN (-3850 1000) $PN 1
R 1
J 0
(-3860 1010);
DISPLAY 0.680851 (-3860 1010);
PAINT MONO (-3860 1010);
FORCEPROP 0 LASTPIN (-3850 750) $PN 2
R 1
J 2
(-3860 740);
DISPLAY 0.680851 (-3860 740);
PAINT MONO (-3860 740);
FORCEPROP 0 LAST PACKAGE 0402
J 0
(-3800 1100);
DISPLAY 1.021277 (-3800 1100);
FORCEPROP 1 LAST VALUE 1KOHM
J 0
(-3800 950);
DISPLAY 1.212766 (-3800 950);
PAINT GREEN (-3800 950);
FORCEPROP 1 LAST PATH I95
J 0
(-4047 1005);
DISPLAY 1.212766 (-4047 1005);
PAINT GREEN (-4047 1005);
DISPLAY INVISIBLE (-4047 1005);
FORCEPROP 1 LAST TOLERANCE 1%
J 0
(-4047 1155);
DISPLAY 1.212766 (-4047 1155);
PAINT GREEN (-4047 1155);
DISPLAY INVISIBLE (-4047 1155);
FORCEPROP 1 LAST CLS_PN G155-11001-01
J 0
(-3986 1100);
DISPLAY 1.212766 (-3986 1100);
PAINT GREEN (-3986 1100);
DISPLAY INVISIBLE (-3986 1100);
FORCEPROP 1 LAST CDS_LMAN_SYM_OUTLINE -50,50,50,-100
J 0
(-3850 900);
DISPLAY 0.468085 (-3850 900);
PAINT GREEN (-3850 900);
DISPLAY INVISIBLE (-3850 900);
FORCEPROP 2 LAST CDS_LIB passive
J 0
(-3850 900);
DISPLAY INVISIBLE (-3850 900);
FORCEADD GND_SG..1
(-3900 450);
FORCEPROP 3 LASTPIN (-3850 500) SIG_NAME SG\g
J 0
(-3840 510);
DISPLAY 0.659574 (-3840 510);
PAINT MONO (-3840 510);
DISPLAY INVISIBLE (-3840 510);
FORCEPROP 1 LAST HDL_POWER SG
J 1
(-3845 355);
DISPLAY 0.808511 (-3845 355);
PAINT GREEN (-3845 355);
FORCEPROP 1 LAST PATH I96
J 0
(-3865 450);
DISPLAY 0.808511 (-3865 450);
PAINT GREEN (-3865 450);
DISPLAY INVISIBLE (-3865 450);
FORCEPROP 1 LAST BODY_TYPE PLUMBING
J 0
(-3885 435);
DISPLAY 0.808511 (-3885 435);
PAINT GREEN (-3885 435);
DISPLAY INVISIBLE (-3885 435);
FORCEPROP 1 LAST CDS_LMAN_SYM_OUTLINE 0,0,100,-50
J 0
(-3900 450);
DISPLAY 0.468085 (-3900 450);
PAINT GREEN (-3900 450);
DISPLAY INVISIBLE (-3900 450);
FORCEPROP 2 LAST CDS_LIB cls
J 0
(-3900 450);
DISPLAY INVISIBLE (-3900 450);
FORCEADD VCC..1
(-3900 2550);
FORCEPROP 3 LASTPIN (-3850 2500) SIG_NAME XP3R3V_FPGA\g
J 0
(-3840 2510);
DISPLAY 0.659574 (-3840 2510);
PAINT MONO (-3840 2510);
DISPLAY INVISIBLE (-3840 2510);
FORCEPROP 0 LAST VOLTAGE 3.3V
J 0
(-4150 2700);
DISPLAY 1.021277 (-4150 2700);
DISPLAY BOTH (-4150 2700);
FORCEPROP 1 LAST HDL_POWER XP3R3V_FPGA
J 1
(-3845 2605);
DISPLAY 1.021277 (-3845 2605);
PAINT GREEN (-3845 2605);
FORCEPROP 1 LAST PATH I98
J 0
(-3865 2640);
DISPLAY 0.808511 (-3865 2640);
PAINT GREEN (-3865 2640);
DISPLAY INVISIBLE (-3865 2640);
FORCEPROP 1 LAST BODY_TYPE PLUMBING
J 0
(-3945 2507);
DISPLAY 0.340426 (-3945 2507);
PAINT GREEN (-3945 2507);
DISPLAY INVISIBLE (-3945 2507);
FORCEPROP 2 LAST CDS_LIB cls
J 0
(-3900 2550);
DISPLAY INVISIBLE (-3900 2550);
FORCEPROP 1 LAST CDS_LMAN_SYM_OUTLINE -250,250,250,-250
J 0
(-3900 2550);
DISPLAY 0.468085 (-3900 2550);
PAINT GREEN (-3900 2550);
DISPLAY INVISIBLE (-3900 2550);
FORCEADD SHEET_A1..1
(4600 -800);
FORCEPROP 2 LAST CUSTOM_TXT_CDS <XR_PAGE_TITLE>
J 0
(-10970 10550);
DISPLAY 0.638298 (-10970 10550);
PAINT PINK (-10970 10550);
FORCEPROP 1 LAST CUSTOM_TXT_CDS <DOCNO>
J 0
(2550 -415);
DISPLAY 0.978723 (2550 -415);
FORCEPROP 1 LAST CUSTOM_TXT_CDS <CON_PAGE_NUM>
J 0
(2445 -750);
DISPLAY 0.978723 (2445 -750);
FORCEPROP 1 LAST CUSTOM_TXT_CDS <DATE>
J 0
(3900 -625);
DISPLAY 0.978723 (3900 -625);
FORCEPROP 1 LAST CUSTOM_TXT_CDS <TITLE>
J 1
(2815 -170);
DISPLAY 0.978723 (2815 -170);
FORCEPROP 1 LAST CUSTOM_TXT_CDS <DESIGNER>
J 0
(3900 -200);
DISPLAY 0.978723 (3900 -200);
FORCEPROP 1 LAST CUSTOM_TXT_CDS <CON_TOTAL_PAGES>
J 0
(2755 -750);
DISPLAY 0.808511 (2755 -750);
FORCEPROP 1 LAST CUSTOM_TXT_CDS <ASSY_PN>
J 0
(2550 -625);
DISPLAY 0.978723 (2550 -625);
FORCEPROP 1 LAST CUSTOM_TXT_CDS <DOCREV>
J 0
(3900 -425);
DISPLAY 0.978723 (3900 -425);
FORCEPROP 1 LAST TITLE TEMPERATURE_SENSOR
J 0
(2000 100);
DISPLAY 3.042553 (2000 100);
PAINT GREEN (2000 100);
FORCEPROP 1 LAST COMMENT_BODY TRUE
J 0
(4610 -745);
DISPLAY 0.808511 (4610 -745);
DISPLAY INVISIBLE (4610 -745);
FORCEPROP 2 LAST CDS_LIB cls
J 0
(4600 -800);
DISPLAY INVISIBLE (4600 -800);
FORCEPROP 1 LAST CDS_LMAN_SYM_OUTLINE -15850,11500,200,-200
J 0
(4600 -800);
DISPLAY 0.468085 (4600 -800);
PAINT GREEN (4600 -800);
DISPLAY INVISIBLE (4600 -800);
FORCEPROP 2 LAST PAGE_BORDER TRUE
J 0
(-10970 10550);
DISPLAY 0.638298 (-10970 10550);
PAINT PINK (-10970 10550);
DISPLAY INVISIBLE (-10970 10550);
FORCEPROP 2 LAST CDS_XR_PAGE_TITLE CR-17 : @TIMECARD_LIB.TIMECARD(SCH_1):PAGE17
J 0
(-10970 10550);
DISPLAY 0.638298 (-10970 10550);
PAINT PINK (-10970 10550);
DISPLAY INVISIBLE (-10970 10550);
WIRE 16 -1 (-1200 2000)(-1200 2100);
WIRE 16 -1 (-1150 4850)(-1150 4950);
WIRE 16 -1 (-1350 8000)(-1350 8100);
WIRE 16 -1 (-2100 7500)(-1350 7500);
WIRE 16 -1 (100 7500)(-1350 7500);
FORCEPROP 2 LAST SIG_NAME FPGA_IN_LM75B_INT1_N
J 0
(-910 7510);
DISPLAY 1.021277 (-910 7510);
WIRE 16 -1 (-1350 7750)(-1350 7500);
WIRE 16 -1 (-550 3850)(-550 3750);
WIRE 16 -1 (-550 3750)(-797 3750);
WIRE 16 -1 (-950 3750)(-797 3750);
WIRE 16 -1 (-797 3250)(-797 3750);
WIRE 16 -1 (-1300 3250)(-797 3250);
WIRE 16 -1 (-1150 4600)(-1150 4350);
WIRE 16 -1 (300 4350)(-1150 4350);
FORCEPROP 2 LAST SIG_NAME FPGA_IN_LM75B_INT2_N
J 0
(-660 4360);
DISPLAY 1.021277 (-660 4360);
WIRE 16 -1 (-2100 4350)(-1150 4350);
WIRE 16 -1 (-2100 1500)(-1200 1500);
WIRE 16 -1 (250 1500)(-1200 1500);
FORCEPROP 2 LAST SIG_NAME FPGA_IN_LM75B_INT3_N
J 0
(-760 1510);
DISPLAY 1.021277 (-760 1510);
WIRE 16 -1 (-1200 1750)(-1200 1500);
WIRE 16 -1 (-3850 6615)(-3400 6615);
WIRE 16 -1 (-3850 6750)(-3850 6615);
WIRE 16 -1 (-3850 6615)(-3850 6500);
WIRE 16 -1 (-3020 6615)(-3400 6615);
WIRE 16 -1 (-3400 6750)(-3400 6615);
WIRE 16 -1 (-3020 6740)(-3020 6615);
WIRE 16 -1 (-2050 6200)(-2050 6400);
WIRE 16 -1 (-1550 6400)(-2050 6400);
WIRE 16 -1 (-2050 6900)(-2050 6400);
WIRE 16 -1 (-2050 6900)(-1850 6900);
WIRE 16 -1 (-3000 8250)(-3000 8400);
WIRE 16 -1 (-3000 8400)(-3400 8400);
WIRE 16 -1 (-3400 8400)(-3400 8250);
WIRE 16 -1 (-3850 8400)(-3400 8400);
WIRE 16 -1 (-3850 8400)(-3850 8250);
WIRE 16 -1 (-3850 8400)(-5350 8400);
WIRE 16 -1 (-5350 8250)(-5350 8400);
WIRE 16 -1 (-5900 8400)(-5350 8400);
WIRE 16 -1 (-5900 8250)(-5900 8400);
WIRE 16 -1 (-5900 8500)(-5900 8400);
WIRE 16 -1 (-1300 6400)(-797 6400);
WIRE 16 -1 (-797 6400)(-797 6900);
WIRE 16 -1 (-550 6900)(-797 6900);
WIRE 16 -1 (-950 6900)(-797 6900);
WIRE 16 -1 (-550 7000)(-550 6900);
WIRE 16 -1 (-2050 3050)(-2050 3250);
WIRE 16 -1 (-1550 3250)(-2050 3250);
WIRE 16 -1 (-2050 3750)(-2050 3250);
WIRE 16 -1 (-2050 3750)(-1850 3750);
WIRE 16 -1 (-3850 3465)(-3400 3465);
WIRE 16 -1 (-3850 3600)(-3850 3465);
WIRE 16 -1 (-3850 3465)(-3850 3350);
WIRE 16 -1 (-3020 3465)(-3400 3465);
WIRE 16 -1 (-3400 3600)(-3400 3465);
WIRE 16 -1 (-3020 3590)(-3020 3465);
WIRE 16 -1 (-3000 5100)(-3000 5250);
WIRE 16 -1 (-3000 5250)(-3400 5250);
WIRE 16 -1 (-3850 5250)(-3400 5250);
WIRE 16 -1 (-3400 5250)(-3400 5100);
WIRE 16 -1 (-3850 5400)(-3850 5250);
WIRE 16 -1 (-3850 5250)(-3850 5100);
WIRE 16 -1 (-1300 400)(-797 400);
WIRE 16 -1 (-797 400)(-797 900);
WIRE 16 -1 (-950 900)(-797 900);
WIRE 16 -1 (-550 900)(-797 900);
WIRE 16 -1 (-550 1000)(-550 900);
WIRE 16 -1 (-2050 900)(-1850 900);
WIRE 16 -1 (-2050 900)(-2050 400);
WIRE 16 -1 (-1550 400)(-2050 400);
WIRE 16 -1 (-2050 200)(-2050 400);
WIRE 16 -1 (-3850 615)(-3400 615);
WIRE 16 -1 (-3850 750)(-3850 615);
WIRE 16 -1 (-3850 615)(-3850 500);
WIRE 16 -1 (-3020 615)(-3400 615);
WIRE 16 -1 (-3400 750)(-3400 615);
WIRE 16 -1 (-3020 740)(-3020 615);
WIRE 16 -1 (-3000 2250)(-3000 2400);
WIRE 16 -1 (-3000 2400)(-3400 2400);
WIRE 16 -1 (-3400 2400)(-3400 2250);
WIRE 16 -1 (-3850 2400)(-3400 2400);
WIRE 16 -1 (-3850 2500)(-3850 2400);
WIRE 16 -1 (-3850 2400)(-3850 2250);
WIRE 16 -1 (-2800 1600)(-5450 1600);
FORCEPROP 2 LAST SIG_NAME R_LM75B_3_I2C_SDA
J 0
(-4810 1610);
DISPLAY 1.021277 (-4810 1610);
WIRE 16 -1 (-2800 1700)(-6300 1700);
WIRE 16 -1 (-6300 1700)(-6300 4550);
WIRE 16 -1 (-2800 4550)(-6300 4550);
WIRE 16 -1 (-6300 4550)(-6300 7700);
WIRE 16 -1 (-5350 7700)(-6300 7700);
WIRE 16 -1 (-8300 7700)(-6300 7700);
FORCEPROP 2 LAST SIG_NAME LM75B_I2C_SCL
J 0
(-8260 7710);
DISPLAY 1.021277 (-8260 7710);
WIRE 16 -1 (-2800 7700)(-5350 7700);
WIRE 16 -1 (-5350 8000)(-5350 7700);
WIRE 16 -1 (-3020 990)(-3020 1200);
WIRE 16 -1 (-3000 1200)(-3020 1200);
WIRE 16 -1 (-3000 2000)(-3000 1200);
WIRE 16 -1 (-2800 1200)(-3000 1200);
WIRE 16 -1 (-2800 7200)(-3000 7200);
WIRE 16 -1 (-3000 8000)(-3000 7200);
WIRE 16 -1 (-3000 7200)(-3020 7200);
WIRE 16 -1 (-3020 6990)(-3020 7200);
WIRE 16 -1 (-2800 4450)(-5450 4450);
FORCEPROP 2 LAST SIG_NAME R_LM75B_2_I2C_SDA
J 0
(-4910 4460);
DISPLAY 1.021277 (-4910 4460);
WIRE 16 -1 (-5700 1600)(-6400 1600);
WIRE 16 -1 (-6400 4450)(-6400 1600);
WIRE 16 -1 (-5700 4450)(-6400 4450);
WIRE 16 -1 (-6400 4450)(-6400 7600);
WIRE 16 -1 (-5900 7600)(-6400 7600);
WIRE 16 -1 (-8300 7600)(-6400 7600);
FORCEPROP 2 LAST SIG_NAME LM75B_I2C_SDA
J 0
(-8260 7610);
DISPLAY 1.021277 (-8260 7610);
WIRE 16 -1 (-5450 7600)(-5900 7600);
WIRE 16 -1 (-5900 8000)(-5900 7600);
WIRE 16 -1 (-2800 7600)(-5200 7600);
FORCEPROP 2 LAST SIG_NAME R_LM75B_1_I2C_SDA
J 0
(-4760 7610);
DISPLAY 1.021277 (-4760 7610);
WIRE 16 -1 (-3400 8000)(-3400 7300);
WIRE 16 -1 (-2800 7300)(-3400 7300);
WIRE 16 -1 (-3400 7000)(-3400 7300);
WIRE 16 -1 (-2800 4050)(-3000 4050);
WIRE 16 -1 (-3000 4850)(-3000 4050);
WIRE 16 -1 (-3000 4050)(-3020 4050);
WIRE 16 -1 (-3020 3840)(-3020 4050);
WIRE 16 -1 (-3850 2000)(-3850 1400);
WIRE 16 -1 (-2800 1400)(-3850 1400);
WIRE 16 -1 (-3850 1000)(-3850 1400);
WIRE 16 -1 (-3400 2000)(-3400 1300);
WIRE 16 -1 (-2800 1300)(-3400 1300);
WIRE 16 -1 (-3400 1000)(-3400 1300);
WIRE 16 -1 (-3400 4850)(-3400 4150);
WIRE 16 -1 (-2800 4150)(-3400 4150);
WIRE 16 -1 (-3400 3850)(-3400 4150);
WIRE 16 -1 (-3850 4850)(-3850 4250);
WIRE 16 -1 (-2800 4250)(-3850 4250);
WIRE 16 -1 (-3850 3850)(-3850 4250);
WIRE 16 -1 (-3850 8000)(-3850 7400);
WIRE 16 -1 (-2800 7400)(-3850 7400);
WIRE 16 -1 (-3850 7000)(-3850 7400);
DOT 1 (-1350 7500);
DOT 1 (-1150 4350);
DOT 1 (-797 3750);
DOT 1 (-1200 1500);
DOT 1 (-797 900);
DOT 1 (-3400 2400);
DOT 1 (-797 6900);
DOT 1 (-6400 4450);
DOT 1 (-6400 7600);
DOT 1 (-6300 4550);
DOT 1 (-3850 6615);
DOT 1 (-5900 7600);
DOT 1 (-5350 7700);
DOT 1 (-5350 8400);
DOT 1 (-5900 8400);
DOT 1 (-3850 8400);
DOT 1 (-3850 7400);
DOT 1 (-6300 7700);
DOT 1 (-3000 4050);
DOT 1 (-3850 615);
DOT 1 (-3400 615);
DOT 1 (-2050 400);
DOT 1 (-3850 1400);
DOT 1 (-3400 1300);
DOT 1 (-3850 3465);
DOT 1 (-3850 4250);
DOT 1 (-3400 3465);
DOT 1 (-3400 4150);
DOT 1 (-2050 3250);
DOT 1 (-3850 5250);
DOT 1 (-3400 5250);
DOT 1 (-3400 6615);
DOT 1 (-3400 7300);
DOT 1 (-3000 7200);
DOT 1 (-3400 8400);
DOT 1 (-2050 6400);
DOT 1 (-3000 1200);
DOT 1 (-3850 2400);
FORCENOTE
LM75B_#1
(-2650 8400) 0;
DISPLAY LEFT (-2650 8400);
DISPLAY 2.510638 (-2650 8400);
FORCENOTE
LM75B_#2
(-2550 5150) 0;
DISPLAY LEFT (-2550 5150);
DISPLAY 2.510638 (-2550 5150);
FORCENOTE
I2C ADDRESS=1001 010X
(-5650 1050) 0;
DISPLAY LEFT (-5650 1050);
DISPLAY 1.595745 (-5650 1050);
FORCENOTE
0X4A
(-4800 900) 0;
DISPLAY LEFT (-4800 900);
DISPLAY 1.595745 (-4800 900);
FORCENOTE
TEMPERATURE_SENSOR
(-4750 9300) 0;
DISPLAY LEFT (-4750 9300);
DISPLAY 3.936170 (-4750 9300);
FORCENOTE
I2C ADDRESS=1001 001X
(-5600 3800) 0;
DISPLAY LEFT (-5600 3800);
DISPLAY 1.595745 (-5600 3800);
FORCENOTE
I2C ADDRESS=1001 000X
(-5650 7000) 0;
DISPLAY LEFT (-5650 7000);
DISPLAY 1.595745 (-5650 7000);
FORCENOTE
LM75B_#3
(-2550 2300) 0;
DISPLAY LEFT (-2550 2300);
DISPLAY 2.510638 (-2550 2300);
FORCENOTE
0X49
(-4750 3650) 0;
DISPLAY LEFT (-4750 3650);
DISPLAY 1.595745 (-4750 3650);
FORCENOTE
0X48
(-4800 6850) 0;
DISPLAY LEFT (-4800 6850);
DISPLAY 1.595745 (-4800 6850);
QUIT
